FILE_TYPE = MACRO_DRAWING;
SET COLOR_WIRE YELLOW;
SET COLOR_PROP ORANGE;
SET COLOR_DOT WHITE;
SET COLOR_ARC YELLOW;
SET COLOR_BODY GREEN;
SET COLOR_NOTE PURPLE;
SET PROP_DISPLAY VALUE;
SET PAGE_NUMBER P385;
FORCEADD OFFPAGE..1
R 2
(-525 5400);
FORCEPROP 2 LAST $XR1 277 
J 0
(-249 5400);
DISPLAY 0.638298 (-249 5400);
PAINT MONO (-249 5400);
FORCEPROP 2 LAST $XR0 81 
J 0
(-339 5400);
DISPLAY 0.638298 (-339 5400);
PAINT MONO (-339 5400);
FORCEPROP 2 LAST CDS_LIB standard
J 0
(-525 5400);
DISPLAY INVISIBLE (-525 5400);
FORCEPROP 1 LAST OFFPAGE TRUE
J 2
(-850 5275);
DISPLAY 0.872340 (-850 5275);
PAINT GREEN (-850 5275);
DISPLAY INVISIBLE (-850 5275);
FORCEPROP 1 LAST COMMENT_BODY TRUE
J 2
(-650 5300);
DISPLAY 0.872340 (-650 5300);
PAINT GREEN (-650 5300);
DISPLAY INVISIBLE (-650 5300);
FORCEPROP 2 LAST PATH I100
J 0
(-225 5450);
DISPLAY 0.680851 (-225 5450);
DISPLAY INVISIBLE (-225 5450);
FORCEADD P1V0..1
(-1475 6250);
FORCEPROP 3 LASTPIN (-1475 6200) SIG_NAME P1V8_CPU0_RT_1D\g
J 0
(-1465 6210);
DISPLAY 0.659574 (-1465 6210);
PAINT MONO (-1465 6210);
DISPLAY INVISIBLE (-1465 6210);
FORCEPROP 1 LAST HDL_POWER P1V8_CPU0_RT_1D
J 1
(-1475 6300);
DISPLAY 0.489362 (-1475 6300);
PAINT SKYBLUE (-1475 6300);
FORCEPROP 2 LAST CDS_LIB pure_quanta_power
J 0
(-1475 6250);
DISPLAY INVISIBLE (-1475 6250);
FORCEPROP 1 LAST PATH I101
J 0
(-1425 6275);
DISPLAY 0.872340 (-1425 6275);
PAINT AQUA (-1425 6275);
DISPLAY INVISIBLE (-1425 6275);
FORCEADD OFFPAGE..5
R 2
(-1925 5625);
FORCEPROP 2 LAST $XR0 277 
J 0
(-1736 5625);
DISPLAY 0.638298 (-1736 5625);
PAINT MONO (-1736 5625);
FORCEPROP 2 LAST CDS_LIB standard
J 0
(-1925 5625);
DISPLAY INVISIBLE (-1925 5625);
FORCEPROP 1 LAST OFFPAGE TRUE
J 2
(-2250 5500);
DISPLAY 0.872340 (-2250 5500);
PAINT GREEN (-2250 5500);
DISPLAY INVISIBLE (-2250 5500);
FORCEPROP 1 LAST COMMENT_BODY TRUE
J 2
(-2025 5550);
DISPLAY 0.872340 (-2025 5550);
PAINT GREEN (-2025 5550);
DISPLAY INVISIBLE (-2025 5550);
FORCEPROP 2 LAST PATH I102
J 0
(-1725 5675);
DISPLAY 0.680851 (-1725 5675);
DISPLAY INVISIBLE (-1725 5675);
FORCEADD OFFPAGE..5
R 2
(-1925 5525);
FORCEPROP 2 LAST $XR0 277 
J 0
(-1736 5525);
DISPLAY 0.638298 (-1736 5525);
PAINT MONO (-1736 5525);
FORCEPROP 2 LAST CDS_LIB standard
J 0
(-1925 5525);
DISPLAY INVISIBLE (-1925 5525);
FORCEPROP 1 LAST OFFPAGE TRUE
J 2
(-2250 5400);
DISPLAY 0.872340 (-2250 5400);
PAINT GREEN (-2250 5400);
DISPLAY INVISIBLE (-2250 5400);
FORCEPROP 1 LAST COMMENT_BODY TRUE
J 2
(-2025 5450);
DISPLAY 0.872340 (-2025 5450);
PAINT GREEN (-2025 5450);
DISPLAY INVISIBLE (-2025 5450);
FORCEPROP 2 LAST PATH I103
J 0
(-1725 5575);
DISPLAY 0.680851 (-1725 5575);
DISPLAY INVISIBLE (-1725 5575);
FORCEADD Q_RES..1
(-2700 3200);
FORCEPROP 1 LAST LOCATION R1364
J 0
(-2825 3200);
DISPLAY 0.787234 (-2825 3200);
PAINT WHITE (-2825 3200);
FORCEPROP 0 LAST $SEC 1
J 0
(-2325 3250);
DISPLAY 0.680851 (-2325 3250);
PAINT MONO (-2325 3250);
DISPLAY INVISIBLE (-2325 3250);
FORCEPROP 0 LAST CDS_SEC 1
J 0
(-2325 3250);
DISPLAY 0.680851 (-2325 3250);
DISPLAY INVISIBLE (-2325 3250);
FORCEPROP 1 LASTPIN (-2800 3200) $PN 1
J 0
(-2788 3212);
DISPLAY 0.787234 (-2788 3212);
PAINT MONO (-2788 3212);
FORCEPROP 1 LASTPIN (-2600 3200) $PN 2
J 0
(-2638 3212);
DISPLAY 0.787234 (-2638 3212);
PAINT MONO (-2638 3212);
FORCEPROP 1 LAST VALUE 1K
J 2
(-2500 3200);
DISPLAY 0.638298 (-2500 3200);
FORCEPROP 1 LAST PACK_TYPE 0201LF
J 0
(-2325 3200);
DISPLAY 0.638298 (-2325 3200);
FORCEPROP 1 LAST MATERIAL CHIP
J 0
(-2475 3200);
DISPLAY 0.638298 (-2475 3200);
FORCEPROP 2 LAST CDS_LIB pure_quanta
J 0
(-2700 3200);
DISPLAY INVISIBLE (-2700 3200);
FORCEPROP 1 LAST WATTAGE 1/20W
J 2
(-2725 3050);
DISPLAY 0.638298 (-2725 3050);
DISPLAY INVISIBLE (-2725 3050);
FORCEPROP 1 LAST TOLERANCE 1%
J 0
(-2700 3100);
DISPLAY 0.638298 (-2700 3100);
DISPLAY INVISIBLE (-2700 3100);
FORCEPROP 1 LAST PATH I111
J 0
(-2750 3350);
DISPLAY 0.978723 (-2750 3350);
PAINT WHITE (-2750 3350);
DISPLAY INVISIBLE (-2750 3350);
FORCEPROP 1 LAST PART_NUMBER CS21001FE07
J 0
(-2750 3300);
DISPLAY 0.978723 (-2750 3300);
DISPLAY INVISIBLE (-2750 3300);
FORCEADD UNIVERSAL_GND..1
R 1
(-1950 3200);
FORCEPROP 3 LASTPIN (-2000 3200) SIG_NAME GND\g
J 0
(-1990 3210);
DISPLAY 0.659574 (-1990 3210);
PAINT MONO (-1990 3210);
DISPLAY INVISIBLE (-1990 3210);
FORCEPROP 2 LAST CDS_LIB pure_quanta_power
J 0
(-1950 3200);
DISPLAY INVISIBLE (-1950 3200);
FORCEPROP 1 LAST HDL_POWER GND
R 1
J 1
(-1875 3225);
DISPLAY 0.872340 (-1875 3225);
PAINT GREEN (-1875 3225);
DISPLAY INVISIBLE (-1875 3225);
FORCEPROP 1 LAST PATH I112
R 1
J 0
(-1950 3275);
DISPLAY 0.872340 (-1950 3275);
PAINT AQUA (-1950 3275);
DISPLAY INVISIBLE (-1950 3275);
FORCEADD OFFPAGE..1
R 2
(-2400 2650);
FORCEPROP 2 LAST $XR0 277 
J 0
(-2214 2650);
DISPLAY 0.638298 (-2214 2650);
PAINT MONO (-2214 2650);
FORCEPROP 2 LAST CDS_LIB standard
J 0
(-2400 2650);
DISPLAY INVISIBLE (-2400 2650);
FORCEPROP 1 LAST OFFPAGE TRUE
J 2
(-2725 2525);
DISPLAY 0.872340 (-2725 2525);
DISPLAY INVISIBLE (-2725 2525);
FORCEPROP 1 LAST COMMENT_BODY TRUE
J 2
(-2525 2550);
DISPLAY 0.872340 (-2525 2550);
PAINT GREEN (-2525 2550);
DISPLAY INVISIBLE (-2525 2550);
FORCEPROP 2 LAST PATH I113
J 0
(-2225 2725);
DISPLAY 0.680851 (-2225 2725);
DISPLAY INVISIBLE (-2225 2725);
FORCEADD Q_RES..2
(-1350 3350);
FORCEPROP 1 LAST LOCATION R1370
J 0
(-1305 3475);
DISPLAY 0.787234 (-1305 3475);
PAINT WHITE (-1305 3475);
FORCEPROP 0 LAST $SEC 1
J 0
(-1300 3525);
DISPLAY 0.680851 (-1300 3525);
PAINT MONO (-1300 3525);
DISPLAY INVISIBLE (-1300 3525);
FORCEPROP 0 LAST CDS_SEC 1
J 0
(-1300 3525);
DISPLAY 0.680851 (-1300 3525);
DISPLAY INVISIBLE (-1300 3525);
FORCEPROP 1 LASTPIN (-1350 3450) $PN 1
J 0
(-1345 3412);
DISPLAY 0.787234 (-1345 3412);
PAINT MONO (-1345 3412);
FORCEPROP 1 LASTPIN (-1350 3250) $PN 2
J 0
(-1345 3260);
DISPLAY 0.787234 (-1345 3260);
PAINT MONO (-1345 3260);
FORCEPROP 1 LAST TOLERANCE 1%
J 0
(-1305 3375);
DISPLAY 0.787234 (-1305 3375);
FORCEPROP 1 LAST MATERIAL CHIP
J 0
(-1310 3275);
DISPLAY 0.787234 (-1310 3275);
FORCEPROP 1 LAST PACK_TYPE 0201LF
J 0
(-1310 3175);
DISPLAY 0.787234 (-1310 3175);
FORCEPROP 1 LAST WATTAGE 1/20W
J 0
(-1310 3325);
DISPLAY 0.787234 (-1310 3325);
FORCEPROP 1 LAST VALUE 10K
J 0
(-1305 3425);
DISPLAY 0.787234 (-1305 3425);
FORCEPROP 2 LAST CDS_LIB pure_quanta
J 0
(-1350 3350);
DISPLAY INVISIBLE (-1350 3350);
FORCEPROP 1 LAST PATH I114
J 0
(-1300 3525);
DISPLAY 0.978723 (-1300 3525);
PAINT WHITE (-1300 3525);
DISPLAY INVISIBLE (-1300 3525);
FORCEPROP 1 LAST PART_NUMBER CS31001FE17
J 0
(-1310 3225);
DISPLAY 0.510638 (-1310 3225);
DISPLAY INVISIBLE (-1310 3225);
FORCEADD GND..1
(-1350 2950);
FORCEPROP 3 LASTPIN (-1350 3000) SIG_NAME GND\g
J 0
(-1340 3010);
DISPLAY 0.659574 (-1340 3010);
PAINT MONO (-1340 3010);
DISPLAY INVISIBLE (-1340 3010);
FORCEPROP 2 LAST CDS_LIB pure_quanta_power
J 0
(-1350 2950);
DISPLAY INVISIBLE (-1350 2950);
FORCEPROP 1 LAST SIZE 1B
J 0
(-1275 2900);
DISPLAY 0.851064 (-1275 2900);
PAINT GREEN (-1275 2900);
DISPLAY INVISIBLE (-1275 2900);
FORCEPROP 2 LAST BOM_COST MEM
J 0
(-1450 3025);
DISPLAY 0.808511 (-1450 3025);
DISPLAY INVISIBLE (-1450 3025);
FORCEPROP 1 LAST HDL_POWER GND
J 0
(-1350 3100);
DISPLAY 0.851064 (-1350 3100);
PAINT GREEN (-1350 3100);
DISPLAY INVISIBLE (-1350 3100);
FORCEPROP 1 LAST PATH I115
J 0
(-1275 2950);
DISPLAY 0.872340 (-1275 2950);
PAINT AQUA (-1275 2950);
DISPLAY INVISIBLE (-1275 2950);
FORCEADD Q_RES..2
(-1350 3875);
FORCEPROP 1 LAST LOCATION R1369
J 0
(-1305 4000);
DISPLAY 0.787234 (-1305 4000);
PAINT WHITE (-1305 4000);
FORCEPROP 0 LAST $SEC 1
J 0
(-1300 4050);
DISPLAY 0.680851 (-1300 4050);
PAINT MONO (-1300 4050);
DISPLAY INVISIBLE (-1300 4050);
FORCEPROP 0 LAST CDS_SEC 1
J 0
(-1300 4050);
DISPLAY 0.680851 (-1300 4050);
DISPLAY INVISIBLE (-1300 4050);
FORCEPROP 1 LASTPIN (-1350 3975) $PN 1
J 0
(-1345 3937);
DISPLAY 0.787234 (-1345 3937);
PAINT MONO (-1345 3937);
FORCEPROP 1 LASTPIN (-1350 3775) $PN 2
J 0
(-1345 3785);
DISPLAY 0.787234 (-1345 3785);
PAINT MONO (-1345 3785);
FORCEPROP 1 LAST TOLERANCE 1%
J 0
(-1305 3900);
DISPLAY 0.787234 (-1305 3900);
FORCEPROP 1 LAST PACK_TYPE 0201LF
J 0
(-1310 3700);
DISPLAY 0.787234 (-1310 3700);
FORCEPROP 1 LAST VALUE 1K
J 0
(-1305 3950);
DISPLAY 0.787234 (-1305 3950);
FORCEPROP 1 LAST MATERIAL EMPTY
J 0
(-1310 3800);
DISPLAY 0.787234 (-1310 3800);
PAINT RED (-1310 3800);
FORCEPROP 1 LAST WATTAGE 1/20W
J 0
(-1310 3850);
DISPLAY 0.787234 (-1310 3850);
FORCEPROP 2 LAST CDS_LIB pure_quanta
J 0
(-1350 3875);
DISPLAY INVISIBLE (-1350 3875);
FORCEPROP 1 LAST PATH I116
J 0
(-1300 4050);
DISPLAY 0.978723 (-1300 4050);
PAINT WHITE (-1300 4050);
DISPLAY INVISIBLE (-1300 4050);
FORCEPROP 1 LAST PART_NUMBER CS21001FE07
J 0
(-1310 3750);
DISPLAY 0.978723 (-1310 3750);
DISPLAY INVISIBLE (-1310 3750);
FORCEADD P1V0..1
(-1350 4275);
FORCEPROP 3 LASTPIN (-1350 4225) SIG_NAME P1V8_CPU0_RT_1D\g
J 0
(-1340 4235);
DISPLAY 0.659574 (-1340 4235);
PAINT MONO (-1340 4235);
DISPLAY INVISIBLE (-1340 4235);
FORCEPROP 1 LAST HDL_POWER P1V8_CPU0_RT_1D
J 1
(-1350 4325);
DISPLAY 0.489362 (-1350 4325);
PAINT SKYBLUE (-1350 4325);
FORCEPROP 2 LAST CDS_LIB pure_quanta_power
J 0
(-1350 4275);
DISPLAY INVISIBLE (-1350 4275);
FORCEPROP 1 LAST PATH I117
J 0
(-1300 4300);
DISPLAY 0.872340 (-1300 4300);
PAINT AQUA (-1300 4300);
DISPLAY INVISIBLE (-1300 4300);
FORCEADD OFFPAGE..1
R 2
(-500 3600);
FORCEPROP 2 LAST $XR0 277 
J 0
(-314 3600);
DISPLAY 0.638298 (-314 3600);
PAINT MONO (-314 3600);
FORCEPROP 2 LAST CDS_LIB standard
J 0
(-500 3600);
DISPLAY INVISIBLE (-500 3600);
FORCEPROP 1 LAST OFFPAGE TRUE
J 2
(-825 3475);
DISPLAY 0.872340 (-825 3475);
DISPLAY INVISIBLE (-825 3475);
FORCEPROP 1 LAST COMMENT_BODY TRUE
J 2
(-625 3500);
DISPLAY 0.872340 (-625 3500);
PAINT GREEN (-625 3500);
DISPLAY INVISIBLE (-625 3500);
FORCEPROP 2 LAST PATH I118
J 0
(-325 3675);
DISPLAY 0.680851 (-325 3675);
DISPLAY INVISIBLE (-325 3675);
FORCEADD Q_RES..1
(-2675 2250);
FORCEPROP 1 LAST LOCATION R1368
J 0
(-2725 2300);
DISPLAY 0.978723 (-2725 2300);
FORCEPROP 0 LAST $SEC 1
J 0
(-2725 2350);
DISPLAY 0.680851 (-2725 2350);
PAINT MONO (-2725 2350);
DISPLAY INVISIBLE (-2725 2350);
FORCEPROP 0 LAST CDS_SEC 1
J 0
(-2725 2350);
DISPLAY 0.680851 (-2725 2350);
DISPLAY INVISIBLE (-2725 2350);
FORCEPROP 1 LASTPIN (-2775 2250) $PN 1
J 0
(-2763 2262);
DISPLAY 0.787234 (-2763 2262);
PAINT MONO (-2763 2262);
FORCEPROP 1 LASTPIN (-2575 2250) $PN 2
J 0
(-2613 2262);
DISPLAY 0.787234 (-2613 2262);
PAINT MONO (-2613 2262);
FORCEPROP 1 LAST VALUE 4.7K
J 2
(-2425 2250);
DISPLAY 0.638298 (-2425 2250);
FORCEPROP 1 LAST MATERIAL CHIP
J 0
(-2400 2250);
DISPLAY 0.638298 (-2400 2250);
FORCEPROP 1 LAST PACK_TYPE 0201LF
J 0
(-2250 2250);
DISPLAY 0.638298 (-2250 2250);
FORCEPROP 1 LAST WATTAGE 1/20W
J 2
(-2700 2100);
DISPLAY 0.978723 (-2700 2100);
DISPLAY INVISIBLE (-2700 2100);
FORCEPROP 1 LAST TOLERANCE 5%
J 0
(-2675 2150);
DISPLAY 0.978723 (-2675 2150);
DISPLAY INVISIBLE (-2675 2150);
FORCEPROP 2 LAST CDS_LIB pure_quanta
J 0
(-2675 2250);
DISPLAY INVISIBLE (-2675 2250);
FORCEPROP 1 LAST PATH I119
J 0
(-2725 2400);
DISPLAY 0.978723 (-2725 2400);
PAINT WHITE (-2725 2400);
DISPLAY INVISIBLE (-2725 2400);
FORCEPROP 1 LAST PART_NUMBER CS24701JE04
J 0
(-2725 2350);
DISPLAY 0.978723 (-2725 2350);
DISPLAY INVISIBLE (-2725 2350);
FORCEADD UNIVERSAL_GND..1
R 1
(-1950 2250);
FORCEPROP 3 LASTPIN (-2000 2250) SIG_NAME GND\g
J 0
(-1990 2260);
DISPLAY 0.659574 (-1990 2260);
PAINT MONO (-1990 2260);
DISPLAY INVISIBLE (-1990 2260);
FORCEPROP 2 LAST CDS_LIB pure_quanta_power
J 0
(-1950 2250);
DISPLAY INVISIBLE (-1950 2250);
FORCEPROP 1 LAST HDL_POWER GND
R 1
J 1
(-1875 2275);
DISPLAY 0.872340 (-1875 2275);
PAINT GREEN (-1875 2275);
DISPLAY INVISIBLE (-1875 2275);
FORCEPROP 1 LAST PATH I120
R 1
J 0
(-1950 2325);
DISPLAY 0.872340 (-1950 2325);
PAINT AQUA (-1950 2325);
DISPLAY INVISIBLE (-1950 2325);
FORCEADD Q_RES..2
(-8975 3400);
FORCEPROP 1 LAST LOCATION R973
J 0
(-8930 3525);
DISPLAY 0.978723 (-8930 3525);
PAINT WHITE (-8930 3525);
FORCEPROP 0 LAST $SEC 1
J 0
(-8925 3575);
DISPLAY 0.680851 (-8925 3575);
PAINT MONO (-8925 3575);
DISPLAY INVISIBLE (-8925 3575);
FORCEPROP 0 LAST CDS_SEC 1
J 0
(-8925 3575);
DISPLAY 0.680851 (-8925 3575);
DISPLAY INVISIBLE (-8925 3575);
FORCEPROP 1 LASTPIN (-8975 3500) $PN 1
J 0
(-8970 3462);
DISPLAY 0.787234 (-8970 3462);
PAINT MONO (-8970 3462);
FORCEPROP 1 LASTPIN (-8975 3300) $PN 2
J 0
(-8970 3310);
DISPLAY 0.787234 (-8970 3310);
PAINT MONO (-8970 3310);
FORCEPROP 1 LAST PACK_TYPE 0201LF
J 0
(-8935 3225);
DISPLAY 0.978723 (-8935 3225);
FORCEPROP 1 LAST WATTAGE 1/20W
J 0
(-8935 3375);
DISPLAY 0.978723 (-8935 3375);
FORCEPROP 1 LAST TOLERANCE 1%
J 0
(-8930 3425);
DISPLAY 0.978723 (-8930 3425);
FORCEPROP 1 LAST VALUE 200
J 0
(-8930 3475);
DISPLAY 0.978723 (-8930 3475);
FORCEPROP 1 LAST MATERIAL CHIP
J 0
(-8935 3325);
DISPLAY 0.978723 (-8935 3325);
FORCEPROP 2 LAST CDS_LIB pure_quanta
J 0
(-8975 3400);
DISPLAY INVISIBLE (-8975 3400);
FORCEPROP 1 LAST PATH I121
J 0
(-8925 3575);
DISPLAY 0.978723 (-8925 3575);
PAINT WHITE (-8925 3575);
DISPLAY INVISIBLE (-8925 3575);
FORCEPROP 1 LAST PART_NUMBER CS12001FE12
J 0
(-8935 3275);
DISPLAY 0.978723 (-8935 3275);
DISPLAY INVISIBLE (-8935 3275);
FORCEADD OFFPAGE..5
(-2625 1200);
FORCEPROP 2 LAST $XR0 277 
J 0
(-2880 1200);
DISPLAY 0.638298 (-2880 1200);
PAINT MONO (-2880 1200);
FORCEPROP 2 LAST CDS_LIB standard
J 2
(-2625 1200);
DISPLAY INVISIBLE (-2625 1200);
FORCEPROP 1 LAST OFFPAGE TRUE
J 0
(-2300 1075);
DISPLAY 0.872340 (-2300 1075);
PAINT GREEN (-2300 1075);
DISPLAY INVISIBLE (-2300 1075);
FORCEPROP 1 LAST COMMENT_BODY TRUE
J 0
(-2525 1125);
DISPLAY 0.872340 (-2525 1125);
PAINT GREEN (-2525 1125);
DISPLAY INVISIBLE (-2525 1125);
FORCEPROP 2 LAST PATH I122
J 2
(-2800 1275);
DISPLAY 0.680851 (-2800 1275);
DISPLAY INVISIBLE (-2800 1275);
FORCEADD Q_RES..2
(-650 825);
FORCEPROP 1 LAST LOCATION R1365
J 0
(-605 950);
DISPLAY 0.787234 (-605 950);
FORCEPROP 0 LAST $SEC 1
J 0
(-600 1000);
DISPLAY 0.680851 (-600 1000);
PAINT MONO (-600 1000);
DISPLAY INVISIBLE (-600 1000);
FORCEPROP 0 LAST CDS_SEC 1
J 0
(-600 1000);
DISPLAY 0.680851 (-600 1000);
DISPLAY INVISIBLE (-600 1000);
FORCEPROP 1 LASTPIN (-650 925) $PN 1
J 0
(-645 887);
DISPLAY 0.787234 (-645 887);
PAINT MONO (-645 887);
FORCEPROP 1 LASTPIN (-650 725) $PN 2
J 0
(-645 735);
DISPLAY 0.787234 (-645 735);
PAINT MONO (-645 735);
FORCEPROP 1 LAST PACK_TYPE 0201LF
J 0
(-610 650);
DISPLAY 0.787234 (-610 650);
FORCEPROP 1 LAST MATERIAL CHIP
J 0
(-610 750);
DISPLAY 0.787234 (-610 750);
FORCEPROP 1 LAST TOLERANCE 5%
J 0
(-605 850);
DISPLAY 0.787234 (-605 850);
FORCEPROP 1 LAST VALUE 4.7K
J 0
(-605 900);
DISPLAY 0.787234 (-605 900);
FORCEPROP 1 LAST WATTAGE 1/20W
J 0
(-610 800);
DISPLAY 0.787234 (-610 800);
FORCEPROP 2 LAST CDS_LIB pure_quanta
J 0
(-650 825);
DISPLAY INVISIBLE (-650 825);
FORCEPROP 1 LAST PATH I123
J 0
(-600 1000);
DISPLAY 0.978723 (-600 1000);
PAINT WHITE (-600 1000);
DISPLAY INVISIBLE (-600 1000);
FORCEPROP 1 LAST PART_NUMBER CS24701JE04
J 0
(-610 700);
DISPLAY 0.978723 (-610 700);
DISPLAY INVISIBLE (-610 700);
FORCEADD GND..1
(-650 525);
FORCEPROP 3 LASTPIN (-650 575) SIG_NAME GND\g
J 0
(-640 585);
DISPLAY 0.659574 (-640 585);
PAINT MONO (-640 585);
DISPLAY INVISIBLE (-640 585);
FORCEPROP 1 LAST SIZE 1B
J 0
(-575 475);
DISPLAY 0.851064 (-575 475);
PAINT GREEN (-575 475);
DISPLAY INVISIBLE (-575 475);
FORCEPROP 2 LAST BOM_COST MEM
J 0
(-750 600);
DISPLAY 0.808511 (-750 600);
DISPLAY INVISIBLE (-750 600);
FORCEPROP 2 LAST CDS_LIB pure_quanta_power
J 0
(-650 525);
DISPLAY INVISIBLE (-650 525);
FORCEPROP 1 LAST HDL_POWER GND
J 0
(-650 675);
DISPLAY 0.851064 (-650 675);
PAINT GREEN (-650 675);
DISPLAY INVISIBLE (-650 675);
FORCEPROP 1 LAST PATH I128
J 0
(-575 525);
DISPLAY 0.872340 (-575 525);
PAINT AQUA (-575 525);
DISPLAY INVISIBLE (-575 525);
FORCEADD OFFPAGE..5
(-2625 1150);
FORCEPROP 2 LAST $XR0 277 
J 0
(-2880 1150);
DISPLAY 0.638298 (-2880 1150);
PAINT MONO (-2880 1150);
FORCEPROP 2 LAST CDS_LIB standard
J 0
(-2625 1150);
DISPLAY INVISIBLE (-2625 1150);
FORCEPROP 1 LAST OFFPAGE TRUE
J 0
(-2300 1025);
DISPLAY 0.872340 (-2300 1025);
PAINT GREEN (-2300 1025);
DISPLAY INVISIBLE (-2300 1025);
FORCEPROP 1 LAST COMMENT_BODY TRUE
J 0
(-2525 1075);
DISPLAY 0.872340 (-2525 1075);
PAINT GREEN (-2525 1075);
DISPLAY INVISIBLE (-2525 1075);
FORCEPROP 2 LAST PATH I133
J 0
(-2575 1225);
DISPLAY 0.680851 (-2575 1225);
DISPLAY INVISIBLE (-2575 1225);
FORCEADD OFFPAGE..5
(-2625 1100);
FORCEPROP 2 LAST $XR0 277 
J 0
(-2880 1100);
DISPLAY 0.638298 (-2880 1100);
PAINT MONO (-2880 1100);
FORCEPROP 2 LAST CDS_LIB standard
J 0
(-2625 1100);
DISPLAY INVISIBLE (-2625 1100);
FORCEPROP 1 LAST OFFPAGE TRUE
J 0
(-2300 975);
DISPLAY 0.872340 (-2300 975);
PAINT GREEN (-2300 975);
DISPLAY INVISIBLE (-2300 975);
FORCEPROP 1 LAST COMMENT_BODY TRUE
J 0
(-2525 1025);
DISPLAY 0.872340 (-2525 1025);
PAINT GREEN (-2525 1025);
DISPLAY INVISIBLE (-2525 1025);
FORCEPROP 2 LAST PATH I134
J 0
(-2575 1175);
DISPLAY 0.680851 (-2575 1175);
DISPLAY INVISIBLE (-2575 1175);
FORCEADD OFFPAGE..5
(-2625 1050);
FORCEPROP 2 LAST $XR0 277 
J 0
(-2880 1050);
DISPLAY 0.638298 (-2880 1050);
PAINT MONO (-2880 1050);
FORCEPROP 2 LAST CDS_LIB standard
J 0
(-2625 1050);
DISPLAY INVISIBLE (-2625 1050);
FORCEPROP 1 LAST OFFPAGE TRUE
J 0
(-2300 925);
DISPLAY 0.872340 (-2300 925);
PAINT GREEN (-2300 925);
DISPLAY INVISIBLE (-2300 925);
FORCEPROP 1 LAST COMMENT_BODY TRUE
J 0
(-2525 975);
DISPLAY 0.872340 (-2525 975);
PAINT GREEN (-2525 975);
DISPLAY INVISIBLE (-2525 975);
FORCEPROP 2 LAST PATH I135
J 0
(-2575 1125);
DISPLAY 0.680851 (-2575 1125);
DISPLAY INVISIBLE (-2575 1125);
FORCEADD OFFPAGE..1
R 2
(-2725 3600);
FORCEPROP 2 LAST $XR0 277 
J 0
(-2539 3600);
DISPLAY 0.638298 (-2539 3600);
PAINT MONO (-2539 3600);
FORCEPROP 2 LAST CDS_LIB standard
J 0
(-2725 3600);
DISPLAY INVISIBLE (-2725 3600);
FORCEPROP 1 LAST OFFPAGE TRUE
J 2
(-3050 3475);
DISPLAY 0.872340 (-3050 3475);
DISPLAY INVISIBLE (-3050 3475);
FORCEPROP 1 LAST COMMENT_BODY TRUE
J 2
(-2850 3500);
DISPLAY 0.872340 (-2850 3500);
PAINT GREEN (-2850 3500);
DISPLAY INVISIBLE (-2850 3500);
FORCEPROP 2 LAST PATH I136
J 0
(-2550 3675);
DISPLAY 0.680851 (-2550 3675);
DISPLAY INVISIBLE (-2550 3675);
FORCEADD OFFPAGE..1
R 2
(-2725 3500);
FORCEPROP 2 LAST $XR0 277 
J 0
(-2539 3500);
DISPLAY 0.638298 (-2539 3500);
PAINT MONO (-2539 3500);
FORCEPROP 2 LAST CDS_LIB standard
J 0
(-2725 3500);
DISPLAY INVISIBLE (-2725 3500);
FORCEPROP 1 LAST OFFPAGE TRUE
J 2
(-3050 3375);
DISPLAY 0.872340 (-3050 3375);
DISPLAY INVISIBLE (-3050 3375);
FORCEPROP 1 LAST COMMENT_BODY TRUE
J 2
(-2850 3400);
DISPLAY 0.872340 (-2850 3400);
PAINT GREEN (-2850 3400);
DISPLAY INVISIBLE (-2850 3400);
FORCEPROP 2 LAST PATH I137
J 0
(-2550 3575);
DISPLAY 0.680851 (-2550 3575);
DISPLAY INVISIBLE (-2550 3575);
FORCEADD OFFPAGE..1
R 2
(-2725 3400);
FORCEPROP 2 LAST $XR0 277 
J 0
(-2539 3400);
DISPLAY 0.638298 (-2539 3400);
PAINT MONO (-2539 3400);
FORCEPROP 2 LAST CDS_LIB standard
J 0
(-2725 3400);
DISPLAY INVISIBLE (-2725 3400);
FORCEPROP 1 LAST OFFPAGE TRUE
J 2
(-3050 3275);
DISPLAY 0.872340 (-3050 3275);
DISPLAY INVISIBLE (-3050 3275);
FORCEPROP 1 LAST COMMENT_BODY TRUE
J 2
(-2850 3300);
DISPLAY 0.872340 (-2850 3300);
PAINT GREEN (-2850 3300);
DISPLAY INVISIBLE (-2850 3300);
FORCEPROP 2 LAST PATH I138
J 0
(-2550 3475);
DISPLAY 0.680851 (-2550 3475);
DISPLAY INVISIBLE (-2550 3475);
FORCEADD OFFPAGE..1
R 2
(-2725 3300);
FORCEPROP 2 LAST $XR0 277 
J 0
(-2539 3300);
DISPLAY 0.638298 (-2539 3300);
PAINT MONO (-2539 3300);
FORCEPROP 2 LAST CDS_LIB standard
J 0
(-2725 3300);
DISPLAY INVISIBLE (-2725 3300);
FORCEPROP 1 LAST OFFPAGE TRUE
J 2
(-3050 3175);
DISPLAY 0.872340 (-3050 3175);
DISPLAY INVISIBLE (-3050 3175);
FORCEPROP 1 LAST COMMENT_BODY TRUE
J 2
(-2850 3200);
DISPLAY 0.872340 (-2850 3200);
PAINT GREEN (-2850 3200);
DISPLAY INVISIBLE (-2850 3200);
FORCEPROP 2 LAST PATH I139
J 0
(-2550 3375);
DISPLAY 0.680851 (-2550 3375);
DISPLAY INVISIBLE (-2550 3375);
FORCEADD Q_RES..2
(-650 1475);
FORCEPROP 1 LAST LOCATION R1446
J 0
(-605 1600);
DISPLAY 0.787234 (-605 1600);
FORCEPROP 0 LAST $SEC 1
J 0
(-600 1650);
DISPLAY 0.680851 (-600 1650);
PAINT MONO (-600 1650);
DISPLAY INVISIBLE (-600 1650);
FORCEPROP 0 LAST CDS_SEC 1
J 0
(-600 1650);
DISPLAY 0.680851 (-600 1650);
DISPLAY INVISIBLE (-600 1650);
FORCEPROP 1 LASTPIN (-650 1575) $PN 1
J 0
(-645 1537);
DISPLAY 0.787234 (-645 1537);
PAINT MONO (-645 1537);
FORCEPROP 1 LASTPIN (-650 1375) $PN 2
J 0
(-645 1385);
DISPLAY 0.787234 (-645 1385);
PAINT MONO (-645 1385);
FORCEPROP 1 LAST VALUE 4.7K
J 0
(-605 1550);
DISPLAY 0.787234 (-605 1550);
FORCEPROP 1 LAST TOLERANCE 5%
J 0
(-605 1500);
DISPLAY 0.787234 (-605 1500);
FORCEPROP 1 LAST WATTAGE 1/20W
J 0
(-610 1450);
DISPLAY 0.787234 (-610 1450);
FORCEPROP 1 LAST MATERIAL EMPTY
J 0
(-610 1400);
DISPLAY 0.787234 (-610 1400);
PAINT RED (-610 1400);
FORCEPROP 1 LAST PACK_TYPE 0201LF
J 0
(-600 1325);
DISPLAY 0.787234 (-600 1325);
FORCEPROP 2 LAST CDS_LIB pure_quanta
J 2
(-650 1475);
DISPLAY INVISIBLE (-650 1475);
FORCEPROP 1 LAST PATH I143
J 0
(-600 1650);
DISPLAY 0.978723 (-600 1650);
PAINT WHITE (-600 1650);
DISPLAY INVISIBLE (-600 1650);
FORCEPROP 1 LAST PART_NUMBER CS24701JE04
J 0
(-610 1350);
DISPLAY 0.978723 (-610 1350);
DISPLAY INVISIBLE (-610 1350);
FORCEADD P1V0..1
(-650 1775);
FORCEPROP 3 LASTPIN (-650 1725) SIG_NAME P1V8_CPU0_RT_1D\g
J 0
(-640 1735);
DISPLAY 0.659574 (-640 1735);
PAINT MONO (-640 1735);
DISPLAY INVISIBLE (-640 1735);
FORCEPROP 1 LAST HDL_POWER P1V8_CPU0_RT_1D
J 1
(-650 1825);
DISPLAY 0.489362 (-650 1825);
PAINT SKYBLUE (-650 1825);
FORCEPROP 2 LAST CDS_LIB pure_quanta_power
J 0
(-650 1775);
DISPLAY INVISIBLE (-650 1775);
FORCEPROP 1 LAST PATH I144
J 0
(-600 1800);
DISPLAY 0.872340 (-600 1800);
PAINT AQUA (-600 1800);
DISPLAY INVISIBLE (-600 1800);
FORCEADD Q_RES..2
(-925 1450);
FORCEPROP 1 LAST LOCATION R1445
J 0
(-880 1575);
DISPLAY 0.978723 (-880 1575);
FORCEPROP 0 LAST $SEC 1
J 0
(-875 1625);
DISPLAY 0.680851 (-875 1625);
PAINT MONO (-875 1625);
DISPLAY INVISIBLE (-875 1625);
FORCEPROP 0 LAST CDS_SEC 1
J 0
(-875 1625);
DISPLAY 0.680851 (-875 1625);
DISPLAY INVISIBLE (-875 1625);
FORCEPROP 1 LASTPIN (-925 1550) $PN 1
J 0
(-920 1512);
DISPLAY 0.787234 (-920 1512);
PAINT MONO (-920 1512);
FORCEPROP 1 LASTPIN (-925 1350) $PN 2
J 0
(-920 1360);
DISPLAY 0.787234 (-920 1360);
PAINT MONO (-920 1360);
FORCEPROP 1 LAST TOLERANCE 1%
J 0
(-880 1475);
DISPLAY 0.787234 (-880 1475);
FORCEPROP 1 LAST VALUE 1K
J 0
(-880 1525);
DISPLAY 0.787234 (-880 1525);
FORCEPROP 1 LAST PACK_TYPE 0201LF
J 0
(-885 1275);
DISPLAY 0.787234 (-885 1275);
FORCEPROP 1 LAST WATTAGE 1/20W
J 0
(-885 1425);
DISPLAY 0.787234 (-885 1425);
FORCEPROP 1 LAST MATERIAL EMPTY
J 0
(-885 1375);
DISPLAY 0.787234 (-885 1375);
PAINT RED (-885 1375);
FORCEPROP 2 LAST CDS_LIB pure_quanta
J 0
(-925 1450);
DISPLAY INVISIBLE (-925 1450);
FORCEPROP 1 LAST PATH I145
J 0
(-875 1625);
DISPLAY 0.978723 (-875 1625);
PAINT WHITE (-875 1625);
DISPLAY INVISIBLE (-875 1625);
FORCEPROP 1 LAST PART_NUMBER CS21001FE07
J 0
(-885 1325);
DISPLAY 0.978723 (-885 1325);
DISPLAY INVISIBLE (-885 1325);
FORCEADD Q_RES..2
(-1200 1450);
FORCEPROP 1 LAST LOCATION R1439
J 0
(-1155 1575);
DISPLAY 0.978723 (-1155 1575);
FORCEPROP 0 LAST $SEC 1
J 0
(-1150 1625);
DISPLAY 0.680851 (-1150 1625);
PAINT MONO (-1150 1625);
DISPLAY INVISIBLE (-1150 1625);
FORCEPROP 0 LAST CDS_SEC 1
J 0
(-1150 1625);
DISPLAY 0.680851 (-1150 1625);
DISPLAY INVISIBLE (-1150 1625);
FORCEPROP 1 LASTPIN (-1200 1550) $PN 1
J 0
(-1195 1512);
DISPLAY 0.787234 (-1195 1512);
PAINT MONO (-1195 1512);
FORCEPROP 1 LASTPIN (-1200 1350) $PN 2
J 0
(-1195 1360);
DISPLAY 0.787234 (-1195 1360);
PAINT MONO (-1195 1360);
FORCEPROP 1 LAST WATTAGE 1/20W
J 0
(-1160 1425);
DISPLAY 0.787234 (-1160 1425);
FORCEPROP 1 LAST TOLERANCE 5%
J 0
(-1155 1475);
DISPLAY 0.787234 (-1155 1475);
FORCEPROP 1 LAST VALUE 4.7K
J 0
(-1155 1525);
DISPLAY 0.787234 (-1155 1525);
FORCEPROP 1 LAST PACK_TYPE 0201LF
J 0
(-1150 1300);
DISPLAY 0.787234 (-1150 1300);
FORCEPROP 1 LAST MATERIAL EMPTY
J 0
(-1160 1375);
DISPLAY 0.787234 (-1160 1375);
PAINT RED (-1160 1375);
FORCEPROP 2 LAST CDS_LIB pure_quanta
J 0
(-1200 1450);
DISPLAY INVISIBLE (-1200 1450);
FORCEPROP 1 LAST PATH I146
J 0
(-1150 1625);
DISPLAY 0.978723 (-1150 1625);
PAINT WHITE (-1150 1625);
DISPLAY INVISIBLE (-1150 1625);
FORCEPROP 1 LAST PART_NUMBER CS24701JE04
J 0
(-1160 1325);
DISPLAY 0.978723 (-1160 1325);
DISPLAY INVISIBLE (-1160 1325);
FORCEADD Q_RES..2
(-1475 1450);
FORCEPROP 1 LAST LOCATION R1438
J 0
(-1430 1575);
DISPLAY 0.978723 (-1430 1575);
FORCEPROP 0 LAST $SEC 1
J 0
(-1425 1625);
DISPLAY 0.680851 (-1425 1625);
PAINT MONO (-1425 1625);
DISPLAY INVISIBLE (-1425 1625);
FORCEPROP 0 LAST CDS_SEC 1
J 0
(-1425 1625);
DISPLAY 0.680851 (-1425 1625);
DISPLAY INVISIBLE (-1425 1625);
FORCEPROP 1 LASTPIN (-1475 1550) $PN 1
J 0
(-1470 1512);
DISPLAY 0.787234 (-1470 1512);
PAINT MONO (-1470 1512);
FORCEPROP 1 LASTPIN (-1475 1350) $PN 2
J 0
(-1470 1360);
DISPLAY 0.787234 (-1470 1360);
PAINT MONO (-1470 1360);
FORCEPROP 1 LAST TOLERANCE 5%
J 0
(-1430 1475);
DISPLAY 0.787234 (-1430 1475);
FORCEPROP 1 LAST WATTAGE 1/20W
J 0
(-1435 1425);
DISPLAY 0.787234 (-1435 1425);
FORCEPROP 1 LAST VALUE 4.7K
J 0
(-1430 1525);
DISPLAY 0.787234 (-1430 1525);
FORCEPROP 1 LAST PACK_TYPE 0201LF
J 0
(-1425 1300);
DISPLAY 0.787234 (-1425 1300);
FORCEPROP 1 LAST MATERIAL EMPTY
J 0
(-1435 1375);
DISPLAY 0.787234 (-1435 1375);
PAINT RED (-1435 1375);
FORCEPROP 2 LAST CDS_LIB pure_quanta
J 0
(-1475 1450);
DISPLAY INVISIBLE (-1475 1450);
FORCEPROP 1 LAST PATH I147
J 0
(-1425 1625);
DISPLAY 0.978723 (-1425 1625);
PAINT WHITE (-1425 1625);
DISPLAY INVISIBLE (-1425 1625);
FORCEPROP 1 LAST PART_NUMBER CS24701JE04
J 0
(-1435 1325);
DISPLAY 0.978723 (-1435 1325);
DISPLAY INVISIBLE (-1435 1325);
FORCEADD OFFPAGE..1
(-8050 1000);
FORCEPROP 2 LAST $XR0 182 
J 0
(-8332 1000);
DISPLAY 0.638298 (-8332 1000);
PAINT MONO (-8332 1000);
FORCEPROP 2 LAST CDS_LIB standard
J 0
(-8050 1000);
DISPLAY INVISIBLE (-8050 1000);
FORCEPROP 1 LAST OFFPAGE TRUE
J 0
(-7725 875);
DISPLAY 0.872340 (-7725 875);
DISPLAY INVISIBLE (-7725 875);
FORCEPROP 1 LAST COMMENT_BODY TRUE
J 0
(-7925 900);
DISPLAY 0.872340 (-7925 900);
PAINT GREEN (-7925 900);
DISPLAY INVISIBLE (-7925 900);
FORCEPROP 2 LAST PATH I21
J 0
(-8325 1050);
DISPLAY 0.680851 (-8325 1050);
DISPLAY INVISIBLE (-8325 1050);
FORCEADD OFFPAGE..1
(-8050 1150);
FORCEPROP 2 LAST $XR0 182 
J 0
(-8332 1150);
DISPLAY 0.638298 (-8332 1150);
PAINT MONO (-8332 1150);
FORCEPROP 2 LAST CDS_LIB standard
J 0
(-8050 1150);
DISPLAY INVISIBLE (-8050 1150);
FORCEPROP 1 LAST OFFPAGE TRUE
J 0
(-7725 1025);
DISPLAY 0.872340 (-7725 1025);
DISPLAY INVISIBLE (-7725 1025);
FORCEPROP 1 LAST COMMENT_BODY TRUE
J 0
(-7925 1050);
DISPLAY 0.872340 (-7925 1050);
PAINT GREEN (-7925 1050);
DISPLAY INVISIBLE (-7925 1050);
FORCEPROP 2 LAST PATH I22
J 0
(-8325 1200);
DISPLAY 0.680851 (-8325 1200);
DISPLAY INVISIBLE (-8325 1200);
FORCEADD UNIVERSAL_GND..1
(-8975 3125);
FORCEPROP 3 LASTPIN (-8975 3175) SIG_NAME GND\g
J 0
(-8965 3185);
DISPLAY 0.659574 (-8965 3185);
PAINT MONO (-8965 3185);
DISPLAY INVISIBLE (-8965 3185);
FORCEPROP 2 LAST CDS_LIB pure_quanta_power
J 0
(-8975 3125);
DISPLAY INVISIBLE (-8975 3125);
FORCEPROP 1 LAST HDL_POWER GND
J 1
(-8950 3050);
DISPLAY 0.872340 (-8950 3050);
PAINT GREEN (-8950 3050);
DISPLAY INVISIBLE (-8950 3050);
FORCEPROP 1 LAST PATH I23
J 0
(-8900 3125);
DISPLAY 0.872340 (-8900 3125);
PAINT AQUA (-8900 3125);
DISPLAY INVISIBLE (-8900 3125);
FORCEADD Q_RES..2
(-8975 4075);
FORCEPROP 1 LAST LOCATION R972
J 0
(-8930 4200);
DISPLAY 0.787234 (-8930 4200);
FORCEPROP 0 LAST $SEC 1
J 0
(-8925 4250);
DISPLAY 0.680851 (-8925 4250);
PAINT MONO (-8925 4250);
DISPLAY INVISIBLE (-8925 4250);
FORCEPROP 0 LAST CDS_SEC 1
J 0
(-8925 4250);
DISPLAY 0.680851 (-8925 4250);
DISPLAY INVISIBLE (-8925 4250);
FORCEPROP 1 LASTPIN (-8975 4175) $PN 1
J 0
(-8970 4137);
DISPLAY 0.787234 (-8970 4137);
PAINT MONO (-8970 4137);
FORCEPROP 1 LASTPIN (-8975 3975) $PN 2
J 0
(-8970 3985);
DISPLAY 0.787234 (-8970 3985);
PAINT MONO (-8970 3985);
FORCEPROP 1 LAST PACK_TYPE 0201LF
J 0
(-8925 3925);
DISPLAY 0.787234 (-8925 3925);
FORCEPROP 1 LAST MATERIAL EMPTY
J 0
(-8935 4000);
DISPLAY 0.787234 (-8935 4000);
FORCEPROP 1 LAST VALUE 4.7K
J 0
(-8930 4150);
DISPLAY 0.787234 (-8930 4150);
FORCEPROP 1 LAST WATTAGE 1/20W
J 0
(-8935 4050);
DISPLAY 0.787234 (-8935 4050);
FORCEPROP 1 LAST TOLERANCE 5%
J 0
(-8930 4100);
DISPLAY 0.787234 (-8930 4100);
FORCEPROP 2 LAST CDS_LIB pure_quanta
J 0
(-8975 4075);
DISPLAY INVISIBLE (-8975 4075);
FORCEPROP 1 LAST PATH I25
J 0
(-8925 4250);
DISPLAY 0.978723 (-8925 4250);
PAINT WHITE (-8925 4250);
DISPLAY INVISIBLE (-8925 4250);
FORCEPROP 1 LAST PART_NUMBER CS24701JE04
J 0
(-8935 3950);
DISPLAY 0.978723 (-8935 3950);
DISPLAY INVISIBLE (-8935 3950);
FORCEADD P1V0..1
(-8975 4400);
FORCEPROP 3 LASTPIN (-8975 4350) SIG_NAME P1V8_CPU0_RT_1D\g
J 0
(-8965 4360);
DISPLAY 0.659574 (-8965 4360);
PAINT MONO (-8965 4360);
DISPLAY INVISIBLE (-8965 4360);
FORCEPROP 1 LAST HDL_POWER P1V8_CPU0_RT_1D
J 1
(-8975 4450);
DISPLAY 0.489362 (-8975 4450);
PAINT SKYBLUE (-8975 4450);
FORCEPROP 2 LAST CDS_LIB pure_quanta_power
J 0
(-8975 4400);
DISPLAY INVISIBLE (-8975 4400);
FORCEPROP 1 LAST PATH I26
J 0
(-8925 4425);
DISPLAY 0.872340 (-8925 4425);
PAINT AQUA (-8925 4425);
DISPLAY INVISIBLE (-8925 4425);
FORCEADD Q_RES..2
(-8950 5000);
FORCEPROP 1 LAST LOCATION R979
J 0
(-8905 5125);
DISPLAY 0.787234 (-8905 5125);
FORCEPROP 0 LAST $SEC 1
J 0
(-8900 5175);
DISPLAY 0.680851 (-8900 5175);
PAINT MONO (-8900 5175);
DISPLAY INVISIBLE (-8900 5175);
FORCEPROP 0 LAST CDS_SEC 1
J 0
(-8900 5175);
DISPLAY 0.680851 (-8900 5175);
DISPLAY INVISIBLE (-8900 5175);
FORCEPROP 1 LASTPIN (-8950 5100) $PN 1
J 0
(-8945 5062);
DISPLAY 0.787234 (-8945 5062);
PAINT MONO (-8945 5062);
FORCEPROP 1 LASTPIN (-8950 4900) $PN 2
J 0
(-8945 4910);
DISPLAY 0.787234 (-8945 4910);
PAINT MONO (-8945 4910);
FORCEPROP 1 LAST WATTAGE 1/20W
J 0
(-8910 4975);
DISPLAY 0.787234 (-8910 4975);
FORCEPROP 1 LAST VALUE 10K
J 0
(-8905 5075);
DISPLAY 0.787234 (-8905 5075);
FORCEPROP 1 LAST TOLERANCE 1%
J 0
(-8905 5025);
DISPLAY 0.787234 (-8905 5025);
FORCEPROP 1 LAST PACK_TYPE 0201LF
J 0
(-8910 4825);
DISPLAY 0.787234 (-8910 4825);
FORCEPROP 1 LAST MATERIAL CHIP
J 0
(-8910 4925);
DISPLAY 0.787234 (-8910 4925);
FORCEPROP 2 LAST CDS_LIB pure_quanta
J 0
(-8950 5000);
DISPLAY INVISIBLE (-8950 5000);
FORCEPROP 1 LAST PATH I27
J 0
(-8900 5175);
DISPLAY 0.978723 (-8900 5175);
PAINT WHITE (-8900 5175);
DISPLAY INVISIBLE (-8900 5175);
FORCEPROP 1 LAST PART_NUMBER CS31001FE17
J 0
(-8910 4875);
DISPLAY 0.638298 (-8910 4875);
DISPLAY INVISIBLE (-8910 4875);
FORCEADD Q_RES..2
(-8650 5000);
FORCEPROP 1 LAST LOCATION R980
J 0
(-8605 5125);
DISPLAY 0.787234 (-8605 5125);
FORCEPROP 0 LAST $SEC 1
J 0
(-8600 5175);
DISPLAY 0.680851 (-8600 5175);
PAINT MONO (-8600 5175);
DISPLAY INVISIBLE (-8600 5175);
FORCEPROP 0 LAST CDS_SEC 1
J 0
(-8600 5175);
DISPLAY 0.680851 (-8600 5175);
DISPLAY INVISIBLE (-8600 5175);
FORCEPROP 1 LASTPIN (-8650 5100) $PN 1
J 0
(-8645 5062);
DISPLAY 0.787234 (-8645 5062);
PAINT MONO (-8645 5062);
FORCEPROP 1 LASTPIN (-8650 4900) $PN 2
J 0
(-8645 4910);
DISPLAY 0.787234 (-8645 4910);
PAINT MONO (-8645 4910);
FORCEPROP 1 LAST PACK_TYPE 0201LF
J 0
(-8610 4825);
DISPLAY 0.787234 (-8610 4825);
FORCEPROP 1 LAST MATERIAL CHIP
J 0
(-8610 4925);
DISPLAY 0.787234 (-8610 4925);
FORCEPROP 1 LAST WATTAGE 1/20W
J 0
(-8610 4975);
DISPLAY 0.787234 (-8610 4975);
FORCEPROP 1 LAST TOLERANCE 1%
J 0
(-8605 5025);
DISPLAY 0.787234 (-8605 5025);
FORCEPROP 1 LAST VALUE 10K
J 0
(-8605 5075);
DISPLAY 0.787234 (-8605 5075);
FORCEPROP 2 LAST CDS_LIB pure_quanta
J 0
(-8650 5000);
DISPLAY INVISIBLE (-8650 5000);
FORCEPROP 1 LAST PATH I28
J 0
(-8600 5175);
DISPLAY 0.978723 (-8600 5175);
PAINT WHITE (-8600 5175);
DISPLAY INVISIBLE (-8600 5175);
FORCEPROP 1 LAST PART_NUMBER CS31001FE17
J 0
(-8610 4875);
DISPLAY 0.510638 (-8610 4875);
DISPLAY INVISIBLE (-8610 4875);
FORCEADD Q_RES..2
(-8325 5000);
FORCEPROP 1 LAST LOCATION R982
J 0
(-8280 5125);
DISPLAY 0.787234 (-8280 5125);
FORCEPROP 0 LAST $SEC 1
J 0
(-8275 5175);
DISPLAY 0.680851 (-8275 5175);
PAINT MONO (-8275 5175);
DISPLAY INVISIBLE (-8275 5175);
FORCEPROP 0 LAST CDS_SEC 1
J 0
(-8275 5175);
DISPLAY 0.680851 (-8275 5175);
DISPLAY INVISIBLE (-8275 5175);
FORCEPROP 1 LASTPIN (-8325 5100) $PN 1
J 0
(-8320 5062);
DISPLAY 0.787234 (-8320 5062);
PAINT MONO (-8320 5062);
FORCEPROP 1 LASTPIN (-8325 4900) $PN 2
J 0
(-8320 4910);
DISPLAY 0.787234 (-8320 4910);
PAINT MONO (-8320 4910);
FORCEPROP 1 LAST TOLERANCE 5%
J 0
(-8280 5025);
DISPLAY 0.787234 (-8280 5025);
FORCEPROP 1 LAST VALUE 4.7K
J 0
(-8280 5075);
DISPLAY 0.787234 (-8280 5075);
FORCEPROP 1 LAST PACK_TYPE 0201LF
J 0
(-8285 4825);
DISPLAY 0.787234 (-8285 4825);
FORCEPROP 1 LAST WATTAGE 1/20W
J 0
(-8285 4975);
DISPLAY 0.787234 (-8285 4975);
FORCEPROP 1 LAST MATERIAL CHIP
J 0
(-8285 4925);
DISPLAY 0.787234 (-8285 4925);
FORCEPROP 2 LAST CDS_LIB pure_quanta
J 0
(-8325 5000);
DISPLAY INVISIBLE (-8325 5000);
FORCEPROP 1 LAST PATH I29
J 0
(-8275 5175);
DISPLAY 0.978723 (-8275 5175);
PAINT WHITE (-8275 5175);
DISPLAY INVISIBLE (-8275 5175);
FORCEPROP 1 LAST PART_NUMBER CS24701JE04
J 0
(-8285 4875);
DISPLAY 0.978723 (-8285 4875);
DISPLAY INVISIBLE (-8285 4875);
FORCEADD Q_RES..2
(-8950 5950);
FORCEPROP 1 LAST LOCATION R978
J 0
(-8905 6075);
DISPLAY 0.787234 (-8905 6075);
FORCEPROP 0 LAST $SEC 1
J 0
(-8900 6125);
DISPLAY 0.680851 (-8900 6125);
PAINT MONO (-8900 6125);
DISPLAY INVISIBLE (-8900 6125);
FORCEPROP 0 LAST CDS_SEC 1
J 0
(-8900 6125);
DISPLAY 0.680851 (-8900 6125);
DISPLAY INVISIBLE (-8900 6125);
FORCEPROP 1 LASTPIN (-8950 6050) $PN 1
J 0
(-8945 6012);
DISPLAY 0.787234 (-8945 6012);
PAINT MONO (-8945 6012);
FORCEPROP 1 LASTPIN (-8950 5850) $PN 2
J 0
(-8945 5860);
DISPLAY 0.787234 (-8945 5860);
PAINT MONO (-8945 5860);
FORCEPROP 1 LAST TOLERANCE 5%
J 0
(-8905 5975);
DISPLAY 0.787234 (-8905 5975);
FORCEPROP 1 LAST VALUE 4.7K
J 0
(-8905 6025);
DISPLAY 0.787234 (-8905 6025);
FORCEPROP 1 LAST WATTAGE 1/20W
J 0
(-8910 5925);
DISPLAY 0.787234 (-8910 5925);
FORCEPROP 1 LAST MATERIAL EMPTY
J 0
(-8910 5875);
DISPLAY 0.787234 (-8910 5875);
FORCEPROP 1 LAST PACK_TYPE 0201LF
J 0
(-8900 5800);
DISPLAY 0.787234 (-8900 5800);
FORCEPROP 2 LAST CDS_LIB pure_quanta
J 0
(-8950 5950);
DISPLAY INVISIBLE (-8950 5950);
FORCEPROP 1 LAST PATH I30
J 0
(-8900 6125);
DISPLAY 0.978723 (-8900 6125);
PAINT WHITE (-8900 6125);
DISPLAY INVISIBLE (-8900 6125);
FORCEPROP 1 LAST PART_NUMBER CS24701JE04
J 0
(-8910 5825);
DISPLAY 0.978723 (-8910 5825);
DISPLAY INVISIBLE (-8910 5825);
FORCEADD Q_RES..2
(-8325 5950);
FORCEPROP 1 LAST LOCATION R981
J 0
(-8280 6075);
DISPLAY 0.787234 (-8280 6075);
FORCEPROP 0 LAST $SEC 1
J 0
(-8275 6125);
DISPLAY 0.680851 (-8275 6125);
PAINT MONO (-8275 6125);
DISPLAY INVISIBLE (-8275 6125);
FORCEPROP 0 LAST CDS_SEC 1
J 0
(-8275 6125);
DISPLAY 0.680851 (-8275 6125);
DISPLAY INVISIBLE (-8275 6125);
FORCEPROP 1 LASTPIN (-8325 6050) $PN 1
J 0
(-8320 6012);
DISPLAY 0.787234 (-8320 6012);
PAINT MONO (-8320 6012);
FORCEPROP 1 LASTPIN (-8325 5850) $PN 2
J 0
(-8320 5860);
DISPLAY 0.787234 (-8320 5860);
PAINT MONO (-8320 5860);
FORCEPROP 1 LAST MATERIAL EMPTY
J 0
(-8285 5875);
DISPLAY 0.787234 (-8285 5875);
FORCEPROP 1 LAST WATTAGE 1/20W
J 0
(-8285 5925);
DISPLAY 0.787234 (-8285 5925);
FORCEPROP 1 LAST PACK_TYPE 0201LF
J 0
(-8275 5800);
DISPLAY 0.787234 (-8275 5800);
FORCEPROP 1 LAST TOLERANCE 5%
J 0
(-8280 5975);
DISPLAY 0.787234 (-8280 5975);
FORCEPROP 1 LAST VALUE 4.7K
J 0
(-8280 6025);
DISPLAY 0.787234 (-8280 6025);
FORCEPROP 2 LAST CDS_LIB pure_quanta
J 0
(-8325 5950);
DISPLAY INVISIBLE (-8325 5950);
FORCEPROP 1 LAST PATH I31
J 0
(-8275 6125);
DISPLAY 0.978723 (-8275 6125);
PAINT WHITE (-8275 6125);
DISPLAY INVISIBLE (-8275 6125);
FORCEPROP 1 LAST PART_NUMBER CS24701JE04
J 0
(-8285 5825);
DISPLAY 0.978723 (-8285 5825);
DISPLAY INVISIBLE (-8285 5825);
FORCEADD P1V0..1
(-8950 6350);
FORCEPROP 3 LASTPIN (-8950 6300) SIG_NAME P1V8_CPU0_RT_1D\g
J 0
(-8940 6310);
DISPLAY 0.659574 (-8940 6310);
PAINT MONO (-8940 6310);
DISPLAY INVISIBLE (-8940 6310);
FORCEPROP 1 LAST HDL_POWER P1V8_CPU0_RT_1D
J 1
(-8950 6400);
DISPLAY 0.489362 (-8950 6400);
PAINT SKYBLUE (-8950 6400);
FORCEPROP 2 LAST CDS_LIB pure_quanta_power
J 0
(-8950 6350);
DISPLAY INVISIBLE (-8950 6350);
FORCEPROP 1 LAST PATH I32
J 0
(-8900 6375);
DISPLAY 0.872340 (-8900 6375);
PAINT AQUA (-8900 6375);
DISPLAY INVISIBLE (-8900 6375);
FORCEADD OFFPAGE..3
R 2
(-7750 1500);
FORCEPROP 2 LAST $XR1 186 
J 0
(-8150 1500);
DISPLAY 0.638298 (-8150 1500);
PAINT MONO (-8150 1500);
FORCEPROP 2 LAST $XR0 185 
J 0
(-8030 1500);
DISPLAY 0.638298 (-8030 1500);
PAINT MONO (-8030 1500);
FORCEPROP 2 LAST CDS_LIB standard
J 0
(-7750 1500);
DISPLAY INVISIBLE (-7750 1500);
FORCEPROP 1 LAST OFFPAGE TRUE
J 2
(-8075 1375);
DISPLAY 0.872340 (-8075 1375);
PAINT GREEN (-8075 1375);
DISPLAY INVISIBLE (-8075 1375);
FORCEPROP 1 LAST COMMENT_BODY TRUE
J 2
(-7700 1400);
DISPLAY 0.872340 (-7700 1400);
PAINT GREEN (-7700 1400);
DISPLAY INVISIBLE (-7700 1400);
FORCEPROP 2 LAST PATH I33
J 0
(-8025 1550);
DISPLAY 0.680851 (-8025 1550);
DISPLAY INVISIBLE (-8025 1550);
FORCEADD OFFPAGE..5
(-7750 1600);
FORCEPROP 2 LAST $XR1 186 
J 0
(-8155 1600);
DISPLAY 0.638298 (-8155 1600);
PAINT MONO (-8155 1600);
FORCEPROP 2 LAST $XR0 185 
J 0
(-8035 1600);
DISPLAY 0.638298 (-8035 1600);
PAINT MONO (-8035 1600);
FORCEPROP 2 LAST CDS_LIB standard
J 0
(-7750 1600);
DISPLAY INVISIBLE (-7750 1600);
FORCEPROP 1 LAST OFFPAGE TRUE
J 0
(-7425 1475);
DISPLAY 0.872340 (-7425 1475);
PAINT GREEN (-7425 1475);
DISPLAY INVISIBLE (-7425 1475);
FORCEPROP 1 LAST COMMENT_BODY TRUE
J 0
(-7650 1525);
DISPLAY 0.872340 (-7650 1525);
PAINT GREEN (-7650 1525);
DISPLAY INVISIBLE (-7650 1525);
FORCEPROP 2 LAST PATH I34
J 0
(-8000 1650);
DISPLAY 0.680851 (-8000 1650);
DISPLAY INVISIBLE (-8000 1650);
FORCEADD UNIVERSAL_GND..1
(-6300 350);
FORCEPROP 3 LASTPIN (-6300 400) SIG_NAME GND\g
J 0
(-6290 410);
DISPLAY 0.659574 (-6290 410);
PAINT MONO (-6290 410);
DISPLAY INVISIBLE (-6290 410);
FORCEPROP 2 LAST CDS_LIB pure_quanta_power
J 0
(-6300 350);
DISPLAY INVISIBLE (-6300 350);
FORCEPROP 1 LAST HDL_POWER GND
J 1
(-6275 275);
DISPLAY 0.872340 (-6275 275);
PAINT GREEN (-6275 275);
DISPLAY INVISIBLE (-6275 275);
FORCEPROP 1 LAST PATH I35
J 0
(-6225 350);
DISPLAY 0.872340 (-6225 350);
PAINT AQUA (-6225 350);
DISPLAY INVISIBLE (-6225 350);
FORCEADD UNIVERSAL_GND..1
(-6150 350);
FORCEPROP 3 LASTPIN (-6150 400) SIG_NAME GND\g
J 0
(-6140 410);
DISPLAY 0.659574 (-6140 410);
PAINT MONO (-6140 410);
DISPLAY INVISIBLE (-6140 410);
FORCEPROP 2 LAST CDS_LIB pure_quanta_power
J 0
(-6150 350);
DISPLAY INVISIBLE (-6150 350);
FORCEPROP 1 LAST HDL_POWER GND
J 1
(-6125 275);
DISPLAY 0.872340 (-6125 275);
PAINT GREEN (-6125 275);
DISPLAY INVISIBLE (-6125 275);
FORCEPROP 1 LAST PATH I36
J 0
(-6075 350);
DISPLAY 0.872340 (-6075 350);
PAINT AQUA (-6075 350);
DISPLAY INVISIBLE (-6075 350);
FORCEADD Q_RES..2
R 2
(-6300 675);
FORCEPROP 1 LAST LOCATION R623
J 2
(-6345 800);
DISPLAY 0.978723 (-6345 800);
PAINT SKYBLUE (-6345 800);
FORCEPROP 0 LAST $SEC 1
J 0
(-6325 850);
DISPLAY 0.680851 (-6325 850);
PAINT MONO (-6325 850);
DISPLAY INVISIBLE (-6325 850);
FORCEPROP 0 LAST CDS_SEC 1
J 0
(-6325 850);
DISPLAY 0.680851 (-6325 850);
DISPLAY INVISIBLE (-6325 850);
FORCEPROP 1 LASTPIN (-6300 775) $PN 1
J 2
(-6305 737);
DISPLAY 0.787234 (-6305 737);
PAINT MONO (-6305 737);
FORCEPROP 1 LASTPIN (-6300 575) $PN 2
J 2
(-6305 585);
DISPLAY 0.787234 (-6305 585);
PAINT MONO (-6305 585);
FORCEPROP 1 LAST WATTAGE 1/20W
J 2
(-6340 650);
DISPLAY 0.978723 (-6340 650);
FORCEPROP 1 LAST MATERIAL EMPTY
J 2
(-6340 600);
DISPLAY 0.978723 (-6340 600);
FORCEPROP 1 LAST PACK_TYPE 0201LF
J 2
(-6340 500);
DISPLAY 0.978723 (-6340 500);
FORCEPROP 1 LAST VALUE 51.1
J 2
(-6345 750);
DISPLAY 0.978723 (-6345 750);
FORCEPROP 1 LAST TOLERANCE 1%
J 2
(-6345 700);
DISPLAY 0.978723 (-6345 700);
FORCEPROP 2 LAST CDS_LIB pure_quanta
J 0
(-6300 675);
DISPLAY INVISIBLE (-6300 675);
FORCEPROP 1 LAST PATH I37
J 2
(-6350 850);
DISPLAY 0.978723 (-6350 850);
PAINT WHITE (-6350 850);
DISPLAY INVISIBLE (-6350 850);
FORCEPROP 1 LAST PART_NUMBER CS05111FE00
J 2
(-6340 550);
DISPLAY 0.978723 (-6340 550);
DISPLAY INVISIBLE (-6340 550);
FORCEADD Q_RES..2
(-6150 675);
FORCEPROP 1 LAST LOCATION R624
J 0
(-6105 800);
DISPLAY 0.978723 (-6105 800);
PAINT SKYBLUE (-6105 800);
FORCEPROP 0 LAST $SEC 1
J 0
(-6100 850);
DISPLAY 0.680851 (-6100 850);
PAINT MONO (-6100 850);
DISPLAY INVISIBLE (-6100 850);
FORCEPROP 0 LAST CDS_SEC 1
J 0
(-6100 850);
DISPLAY 0.680851 (-6100 850);
DISPLAY INVISIBLE (-6100 850);
FORCEPROP 1 LASTPIN (-6150 775) $PN 1
J 0
(-6145 737);
DISPLAY 0.787234 (-6145 737);
PAINT MONO (-6145 737);
FORCEPROP 1 LASTPIN (-6150 575) $PN 2
J 0
(-6145 585);
DISPLAY 0.787234 (-6145 585);
PAINT MONO (-6145 585);
FORCEPROP 1 LAST VALUE 51.1
J 0
(-6105 750);
DISPLAY 0.978723 (-6105 750);
FORCEPROP 1 LAST MATERIAL EMPTY
J 0
(-6110 600);
DISPLAY 0.978723 (-6110 600);
FORCEPROP 1 LAST WATTAGE 1/20W
J 0
(-6110 650);
DISPLAY 0.978723 (-6110 650);
FORCEPROP 1 LAST TOLERANCE 1%
J 0
(-6105 700);
DISPLAY 0.978723 (-6105 700);
FORCEPROP 1 LAST PACK_TYPE 0201LF
J 0
(-6110 500);
DISPLAY 0.978723 (-6110 500);
FORCEPROP 2 LAST CDS_LIB pure_quanta
J 0
(-6150 675);
DISPLAY INVISIBLE (-6150 675);
FORCEPROP 1 LAST PATH I38
J 0
(-6100 850);
DISPLAY 0.978723 (-6100 850);
PAINT WHITE (-6100 850);
DISPLAY INVISIBLE (-6100 850);
FORCEPROP 1 LAST PART_NUMBER CS05111FE00
J 0
(-6110 550);
DISPLAY 0.978723 (-6110 550);
DISPLAY INVISIBLE (-6110 550);
FORCEADD Q_RES..1
(-6600 1150);
FORCEPROP 1 LAST LOCATION R595
J 0
(-6850 1150);
DISPLAY 0.978723 (-6850 1150);
PAINT SKYBLUE (-6850 1150);
FORCEPROP 2 LAST SEC 1
J 0
(-6650 1350);
DISPLAY 0.680851 (-6650 1350);
PAINT MONO (-6650 1350);
DISPLAY INVISIBLE (-6650 1350);
FORCEPROP 1 LASTPIN (-6700 1150) $PN 1
J 0
(-6688 1162);
DISPLAY 0.787234 (-6688 1162);
PAINT MONO (-6688 1162);
FORCEPROP 1 LASTPIN (-6500 1150) $PN 2
J 0
(-6538 1162);
DISPLAY 0.787234 (-6538 1162);
PAINT MONO (-6538 1162);
FORCEPROP 1 LAST PACK_TYPE 0201LF
J 0
(-6575 1225);
DISPLAY 0.787234 (-6575 1225);
FORCEPROP 1 LAST MATERIAL CHIP
J 0
(-6775 1225);
DISPLAY 0.787234 (-6775 1225);
FORCEPROP 1 LAST TOLERANCE 5%
J 0
(-6775 1275);
DISPLAY 0.787234 (-6775 1275);
FORCEPROP 1 LAST VALUE 0
J 2
(-6800 1275);
DISPLAY 0.787234 (-6800 1275);
FORCEPROP 1 LAST WATTAGE 1/20W
J 2
(-6800 1225);
DISPLAY 0.787234 (-6800 1225);
FORCEPROP 0 LAST SEC_TYPE 0201LF
J 0
(-6650 1350);
DISPLAY 0.680851 (-6650 1350);
DISPLAY INVISIBLE (-6650 1350);
FORCEPROP 2 LAST CDS_LIB pure_quanta
J 0
(-6600 1150);
DISPLAY INVISIBLE (-6600 1150);
FORCEPROP 1 LAST PATH I39
J 0
(-6650 1300);
DISPLAY 0.978723 (-6650 1300);
PAINT WHITE (-6650 1300);
DISPLAY INVISIBLE (-6650 1300);
FORCEPROP 1 LAST PART_NUMBER CS00001JE10
J 0
(-6650 1275);
DISPLAY 0.808511 (-6650 1275);
DISPLAY INVISIBLE (-6650 1275);
FORCEADD Q_RES..1
(-6600 1000);
FORCEPROP 1 LAST LOCATION R596
J 0
(-6850 1000);
DISPLAY 0.978723 (-6850 1000);
PAINT SKYBLUE (-6850 1000);
FORCEPROP 2 LAST SEC 1
J 0
(-6650 1200);
DISPLAY 0.680851 (-6650 1200);
PAINT MONO (-6650 1200);
DISPLAY INVISIBLE (-6650 1200);
FORCEPROP 1 LASTPIN (-6700 1000) $PN 1
J 0
(-6688 1012);
DISPLAY 0.787234 (-6688 1012);
PAINT MONO (-6688 1012);
FORCEPROP 1 LASTPIN (-6500 1000) $PN 2
J 0
(-6538 1012);
DISPLAY 0.787234 (-6538 1012);
PAINT MONO (-6538 1012);
FORCEPROP 1 LAST MATERIAL CHIP
J 0
(-6775 1075);
DISPLAY 0.787234 (-6775 1075);
FORCEPROP 1 LAST PACK_TYPE 0201LF
J 0
(-6575 1075);
DISPLAY 0.787234 (-6575 1075);
FORCEPROP 2 LAST SEC_TYPE 0201LF
J 0
(-6650 1200);
DISPLAY 0.680851 (-6650 1200);
DISPLAY INVISIBLE (-6650 1200);
FORCEPROP 1 LAST WATTAGE 1/20W
J 2
(-6800 1075);
DISPLAY 0.787234 (-6800 1075);
DISPLAY INVISIBLE (-6800 1075);
FORCEPROP 1 LAST VALUE 0
J 2
(-6800 1125);
DISPLAY 0.787234 (-6800 1125);
DISPLAY INVISIBLE (-6800 1125);
FORCEPROP 1 LAST TOLERANCE 5%
J 0
(-6775 1125);
DISPLAY 0.787234 (-6775 1125);
DISPLAY INVISIBLE (-6775 1125);
FORCEPROP 2 LAST CDS_LIB pure_quanta
J 0
(-6600 1000);
DISPLAY INVISIBLE (-6600 1000);
FORCEPROP 1 LAST PATH I40
J 0
(-6650 1150);
DISPLAY 0.978723 (-6650 1150);
PAINT WHITE (-6650 1150);
DISPLAY INVISIBLE (-6650 1150);
FORCEPROP 1 LAST PART_NUMBER CS00001JE10
J 0
(-6650 1125);
DISPLAY 0.808511 (-6650 1125);
DISPLAY INVISIBLE (-6650 1125);
FORCEADD Q_RES..1
(-6325 1500);
FORCEPROP 1 LAST LOCATION R667
J 0
(-6575 1525);
DISPLAY 0.978723 (-6575 1525);
PAINT SKYBLUE (-6575 1525);
FORCEPROP 0 LAST $SEC 1
J 0
(-6475 1575);
DISPLAY 0.680851 (-6475 1575);
PAINT MONO (-6475 1575);
DISPLAY INVISIBLE (-6475 1575);
FORCEPROP 0 LAST CDS_SEC 1
J 0
(-6475 1575);
DISPLAY 0.680851 (-6475 1575);
DISPLAY INVISIBLE (-6475 1575);
FORCEPROP 1 LASTPIN (-6425 1500) $PN 1
J 0
(-6413 1512);
DISPLAY 0.787234 (-6413 1512);
PAINT MONO (-6413 1512);
FORCEPROP 1 LASTPIN (-6225 1500) $PN 2
J 0
(-6263 1512);
DISPLAY 0.787234 (-6263 1512);
PAINT MONO (-6263 1512);
FORCEPROP 1 LAST PACK_TYPE 0201LF
J 0
(-6300 1575);
DISPLAY 0.787234 (-6300 1575);
DISPLAY INVISIBLE (-6300 1575);
FORCEPROP 1 LAST WATTAGE 1/20W
J 2
(-6525 1575);
DISPLAY 0.787234 (-6525 1575);
DISPLAY INVISIBLE (-6525 1575);
FORCEPROP 1 LAST MATERIAL CHIP
J 0
(-6500 1575);
DISPLAY 0.787234 (-6500 1575);
DISPLAY INVISIBLE (-6500 1575);
FORCEPROP 2 LAST CDS_LIB pure_quanta
J 0
(-6325 1500);
DISPLAY INVISIBLE (-6325 1500);
FORCEPROP 1 LAST VALUE 49.9
J 2
(-6525 1625);
DISPLAY 0.787234 (-6525 1625);
DISPLAY INVISIBLE (-6525 1625);
FORCEPROP 1 LAST TOLERANCE 1%
J 0
(-6500 1625);
DISPLAY 0.787234 (-6500 1625);
DISPLAY INVISIBLE (-6500 1625);
FORCEPROP 1 LAST PATH I41
J 0
(-6375 1650);
DISPLAY 0.978723 (-6375 1650);
PAINT WHITE (-6375 1650);
DISPLAY INVISIBLE (-6375 1650);
FORCEPROP 1 LAST PART_NUMBER CS04991FE06
J 0
(-6375 1625);
DISPLAY 0.808511 (-6375 1625);
DISPLAY INVISIBLE (-6375 1625);
FORCEADD Q_RES..1
(-6325 1600);
FORCEPROP 1 LAST LOCATION R666
J 0
(-6575 1625);
DISPLAY 0.978723 (-6575 1625);
PAINT SKYBLUE (-6575 1625);
FORCEPROP 0 LAST $SEC 1
J 0
(-6375 1775);
DISPLAY 0.680851 (-6375 1775);
PAINT MONO (-6375 1775);
DISPLAY INVISIBLE (-6375 1775);
FORCEPROP 0 LAST CDS_SEC 1
J 0
(-6375 1775);
DISPLAY 0.680851 (-6375 1775);
DISPLAY INVISIBLE (-6375 1775);
FORCEPROP 1 LASTPIN (-6425 1600) $PN 1
J 0
(-6413 1612);
DISPLAY 0.787234 (-6413 1612);
PAINT MONO (-6413 1612);
FORCEPROP 1 LASTPIN (-6225 1600) $PN 2
J 0
(-6263 1612);
DISPLAY 0.787234 (-6263 1612);
PAINT MONO (-6263 1612);
FORCEPROP 1 LAST MATERIAL CHIP
J 0
(-6500 1675);
DISPLAY 0.787234 (-6500 1675);
FORCEPROP 1 LAST WATTAGE 1/20W
J 2
(-6525 1675);
DISPLAY 0.787234 (-6525 1675);
FORCEPROP 1 LAST PACK_TYPE 0201LF
J 0
(-6300 1675);
DISPLAY 0.787234 (-6300 1675);
FORCEPROP 1 LAST VALUE 49.9
J 2
(-6525 1725);
DISPLAY 0.787234 (-6525 1725);
FORCEPROP 1 LAST TOLERANCE 1%
J 0
(-6500 1725);
DISPLAY 0.787234 (-6500 1725);
FORCEPROP 2 LAST CDS_LIB pure_quanta
J 0
(-6325 1600);
DISPLAY INVISIBLE (-6325 1600);
FORCEPROP 1 LAST PATH I42
J 0
(-6375 1750);
DISPLAY 0.978723 (-6375 1750);
PAINT WHITE (-6375 1750);
DISPLAY INVISIBLE (-6375 1750);
FORCEPROP 1 LAST PART_NUMBER CS04991FE06
J 0
(-6375 1725);
DISPLAY 0.808511 (-6375 1725);
DISPLAY INVISIBLE (-6375 1725);
FORCEADD OFFPAGE..1
(-6150 1900);
FORCEPROP 2 LAST $XR0 277 
J 0
(-6402 1900);
DISPLAY 0.638298 (-6402 1900);
PAINT MONO (-6402 1900);
FORCEPROP 2 LAST CDS_LIB standard
J 0
(-6150 1900);
DISPLAY INVISIBLE (-6150 1900);
FORCEPROP 1 LAST OFFPAGE TRUE
J 0
(-5825 1775);
DISPLAY 0.872340 (-5825 1775);
DISPLAY INVISIBLE (-5825 1775);
FORCEPROP 1 LAST COMMENT_BODY TRUE
J 0
(-6025 1800);
DISPLAY 0.872340 (-6025 1800);
PAINT GREEN (-6025 1800);
DISPLAY INVISIBLE (-6025 1800);
FORCEPROP 2 LAST PATH I43
J 0
(-6400 1950);
DISPLAY 0.680851 (-6400 1950);
DISPLAY INVISIBLE (-6400 1950);
FORCEADD OFFPAGE..3
R 2
(-7650 2750);
FORCEPROP 2 LAST $XR0 184 
J 0
(-7930 2750);
DISPLAY 0.638298 (-7930 2750);
PAINT MONO (-7930 2750);
FORCEPROP 2 LAST CDS_LIB standard
J 0
(-7650 2750);
DISPLAY INVISIBLE (-7650 2750);
FORCEPROP 1 LAST OFFPAGE TRUE
J 2
(-7975 2625);
DISPLAY 0.872340 (-7975 2625);
PAINT GREEN (-7975 2625);
DISPLAY INVISIBLE (-7975 2625);
FORCEPROP 1 LAST COMMENT_BODY TRUE
J 2
(-7600 2650);
DISPLAY 0.872340 (-7600 2650);
PAINT GREEN (-7600 2650);
DISPLAY INVISIBLE (-7600 2650);
FORCEPROP 2 LAST PATH I44
J 0
(-7925 2800);
DISPLAY 0.680851 (-7925 2800);
DISPLAY INVISIBLE (-7925 2800);
FORCEADD OFFPAGE..1
(-7650 2850);
FORCEPROP 2 LAST $XR0 184 
J 0
(-7902 2850);
DISPLAY 0.638298 (-7902 2850);
PAINT MONO (-7902 2850);
FORCEPROP 2 LAST CDS_LIB standard
J 0
(-7650 2850);
DISPLAY INVISIBLE (-7650 2850);
FORCEPROP 1 LAST OFFPAGE TRUE
J 0
(-7325 2725);
DISPLAY 0.872340 (-7325 2725);
DISPLAY INVISIBLE (-7325 2725);
FORCEPROP 1 LAST COMMENT_BODY TRUE
J 0
(-7525 2750);
DISPLAY 0.872340 (-7525 2750);
PAINT GREEN (-7525 2750);
DISPLAY INVISIBLE (-7525 2750);
FORCEPROP 2 LAST PATH I45
J 0
(-7900 2900);
DISPLAY 0.680851 (-7900 2900);
DISPLAY INVISIBLE (-7900 2900);
FORCEADD OFFPAGE..5
R 2
(-7800 3850);
FORCEPROP 2 LAST $XR0 277 
J 0
(-7611 3850);
DISPLAY 0.638298 (-7611 3850);
PAINT MONO (-7611 3850);
FORCEPROP 2 LAST CDS_LIB standard
J 0
(-7800 3850);
DISPLAY INVISIBLE (-7800 3850);
FORCEPROP 1 LAST OFFPAGE TRUE
J 2
(-8125 3725);
DISPLAY 0.872340 (-8125 3725);
PAINT GREEN (-8125 3725);
DISPLAY INVISIBLE (-8125 3725);
FORCEPROP 1 LAST COMMENT_BODY TRUE
J 2
(-7900 3775);
DISPLAY 0.872340 (-7900 3775);
PAINT GREEN (-7900 3775);
DISPLAY INVISIBLE (-7900 3775);
FORCEPROP 2 LAST PATH I46
J 0
(-7600 3900);
DISPLAY 0.680851 (-7600 3900);
DISPLAY INVISIBLE (-7600 3900);
FORCEADD OFFPAGE..1
(-6150 2000);
FORCEPROP 2 LAST $XR0 277 
J 0
(-6402 2000);
DISPLAY 0.638298 (-6402 2000);
PAINT MONO (-6402 2000);
FORCEPROP 2 LAST CDS_LIB standard
J 0
(-6150 2000);
DISPLAY INVISIBLE (-6150 2000);
FORCEPROP 1 LAST OFFPAGE TRUE
J 0
(-5825 1875);
DISPLAY 0.872340 (-5825 1875);
DISPLAY INVISIBLE (-5825 1875);
FORCEPROP 1 LAST COMMENT_BODY TRUE
J 0
(-6025 1900);
DISPLAY 0.872340 (-6025 1900);
PAINT GREEN (-6025 1900);
DISPLAY INVISIBLE (-6025 1900);
FORCEPROP 2 LAST PATH I47
J 0
(-6400 2050);
DISPLAY 0.680851 (-6400 2050);
DISPLAY INVISIBLE (-6400 2050);
FORCEADD OFFPAGE..1
(-6150 2100);
FORCEPROP 2 LAST $XR0 277 
J 0
(-6402 2100);
DISPLAY 0.638298 (-6402 2100);
PAINT MONO (-6402 2100);
FORCEPROP 2 LAST CDS_LIB standard
J 0
(-6150 2100);
DISPLAY INVISIBLE (-6150 2100);
FORCEPROP 1 LAST OFFPAGE TRUE
J 0
(-5825 1975);
DISPLAY 0.872340 (-5825 1975);
DISPLAY INVISIBLE (-5825 1975);
FORCEPROP 1 LAST COMMENT_BODY TRUE
J 0
(-6025 2000);
DISPLAY 0.872340 (-6025 2000);
PAINT GREEN (-6025 2000);
DISPLAY INVISIBLE (-6025 2000);
FORCEPROP 2 LAST PATH I48
J 0
(-6400 2150);
DISPLAY 0.680851 (-6400 2150);
DISPLAY INVISIBLE (-6400 2150);
FORCEADD Q_RES..1
(-6350 2750);
FORCEPROP 1 LAST LOCATION R977
J 0
(-6600 2775);
DISPLAY 0.978723 (-6600 2775);
FORCEPROP 0 LAST $SEC 1
J 0
(-6600 2825);
DISPLAY 0.680851 (-6600 2825);
PAINT MONO (-6600 2825);
DISPLAY INVISIBLE (-6600 2825);
FORCEPROP 0 LAST CDS_SEC 1
J 0
(-6600 2825);
DISPLAY 0.680851 (-6600 2825);
DISPLAY INVISIBLE (-6600 2825);
FORCEPROP 1 LASTPIN (-6450 2750) $PN 1
J 0
(-6438 2762);
DISPLAY 0.787234 (-6438 2762);
PAINT MONO (-6438 2762);
FORCEPROP 1 LASTPIN (-6250 2750) $PN 2
J 0
(-6288 2762);
DISPLAY 0.787234 (-6288 2762);
PAINT MONO (-6288 2762);
FORCEPROP 2 LAST CDS_LIB pure_quanta
J 0
(-6350 2750);
DISPLAY INVISIBLE (-6350 2750);
FORCEPROP 1 LAST PACK_TYPE 0201LF
J 0
(-6325 2825);
DISPLAY 0.787234 (-6325 2825);
DISPLAY INVISIBLE (-6325 2825);
FORCEPROP 1 LAST MATERIAL CHIP
J 0
(-6525 2825);
DISPLAY 0.787234 (-6525 2825);
DISPLAY INVISIBLE (-6525 2825);
FORCEPROP 1 LAST TOLERANCE 5%
J 0
(-6525 2875);
DISPLAY 0.787234 (-6525 2875);
DISPLAY INVISIBLE (-6525 2875);
FORCEPROP 1 LAST VALUE 0
J 2
(-6550 2875);
DISPLAY 0.787234 (-6550 2875);
DISPLAY INVISIBLE (-6550 2875);
FORCEPROP 1 LAST WATTAGE 1/20W
J 2
(-6550 2825);
DISPLAY 0.787234 (-6550 2825);
DISPLAY INVISIBLE (-6550 2825);
FORCEPROP 1 LAST PATH I49
J 0
(-6400 2900);
DISPLAY 0.978723 (-6400 2900);
PAINT WHITE (-6400 2900);
DISPLAY INVISIBLE (-6400 2900);
FORCEPROP 1 LAST PART_NUMBER CS00001JE10
J 0
(-6400 2875);
DISPLAY 0.808511 (-6400 2875);
DISPLAY INVISIBLE (-6400 2875);
FORCEADD Q_RES..1
(-6350 2850);
FORCEPROP 1 LAST LOCATION R976
J 0
(-6600 2875);
DISPLAY 0.978723 (-6600 2875);
FORCEPROP 0 LAST $SEC 1
J 0
(-6400 3025);
DISPLAY 0.680851 (-6400 3025);
PAINT MONO (-6400 3025);
DISPLAY INVISIBLE (-6400 3025);
FORCEPROP 0 LAST CDS_SEC 1
J 0
(-6400 3025);
DISPLAY 0.680851 (-6400 3025);
DISPLAY INVISIBLE (-6400 3025);
FORCEPROP 1 LASTPIN (-6450 2850) $PN 1
J 0
(-6438 2862);
DISPLAY 0.787234 (-6438 2862);
PAINT MONO (-6438 2862);
FORCEPROP 1 LASTPIN (-6250 2850) $PN 2
J 0
(-6288 2862);
DISPLAY 0.787234 (-6288 2862);
PAINT MONO (-6288 2862);
FORCEPROP 1 LAST WATTAGE 1/20W
J 2
(-6550 2925);
DISPLAY 0.787234 (-6550 2925);
FORCEPROP 1 LAST TOLERANCE 5%
J 0
(-6525 2975);
DISPLAY 0.787234 (-6525 2975);
FORCEPROP 1 LAST VALUE 0
J 2
(-6550 2975);
DISPLAY 0.787234 (-6550 2975);
FORCEPROP 1 LAST MATERIAL CHIP
J 0
(-6525 2925);
DISPLAY 0.787234 (-6525 2925);
FORCEPROP 1 LAST PACK_TYPE 0201LF
J 0
(-6325 2925);
DISPLAY 0.787234 (-6325 2925);
FORCEPROP 2 LAST CDS_LIB pure_quanta
J 0
(-6350 2850);
DISPLAY INVISIBLE (-6350 2850);
FORCEPROP 1 LAST PATH I50
J 0
(-6400 3000);
DISPLAY 0.978723 (-6400 3000);
PAINT WHITE (-6400 3000);
DISPLAY INVISIBLE (-6400 3000);
FORCEPROP 1 LAST PART_NUMBER CS00001JE10
J 0
(-6400 2975);
DISPLAY 0.808511 (-6400 2975);
DISPLAY INVISIBLE (-6400 2975);
FORCEADD OFFPAGE..1
(-6025 3300);
FORCEPROP 2 LAST $XR0 277 
J 0
(-6307 3300);
DISPLAY 0.638298 (-6307 3300);
PAINT MONO (-6307 3300);
FORCEPROP 2 LAST CDS_LIB standard
J 0
(-6025 3300);
DISPLAY INVISIBLE (-6025 3300);
FORCEPROP 1 LAST OFFPAGE TRUE
J 0
(-5700 3175);
DISPLAY 0.872340 (-5700 3175);
DISPLAY INVISIBLE (-5700 3175);
FORCEPROP 1 LAST COMMENT_BODY TRUE
J 0
(-5900 3200);
DISPLAY 0.872340 (-5900 3200);
PAINT GREEN (-5900 3200);
DISPLAY INVISIBLE (-5900 3200);
FORCEPROP 2 LAST PATH I51
J 0
(-6300 3350);
DISPLAY 0.680851 (-6300 3350);
DISPLAY INVISIBLE (-6300 3350);
FORCEADD OFFPAGE..1
(-6025 3200);
FORCEPROP 2 LAST $XR0 277 
J 0
(-6307 3200);
DISPLAY 0.638298 (-6307 3200);
PAINT MONO (-6307 3200);
FORCEPROP 2 LAST CDS_LIB standard
J 0
(-6025 3200);
DISPLAY INVISIBLE (-6025 3200);
FORCEPROP 1 LAST OFFPAGE TRUE
J 0
(-5700 3075);
DISPLAY 0.872340 (-5700 3075);
DISPLAY INVISIBLE (-5700 3075);
FORCEPROP 1 LAST COMMENT_BODY TRUE
J 0
(-5900 3100);
DISPLAY 0.872340 (-5900 3100);
PAINT GREEN (-5900 3100);
DISPLAY INVISIBLE (-5900 3100);
FORCEPROP 2 LAST PATH I52
J 0
(-6300 3250);
DISPLAY 0.680851 (-6300 3250);
DISPLAY INVISIBLE (-6300 3250);
FORCEADD PT5161LRS..3
(-4375 2300);
FORCEPROP 1 LAST LOCATION U6010
J 0
(-4875 3925);
DISPLAY 0.723404 (-4875 3925);
PAINT SKYBLUE (-4875 3925);
FORCEPROP 0 LAST $SEC 3
J 0
(-4875 4075);
DISPLAY 0.680851 (-4875 4075);
PAINT MONO (-4875 4075);
DISPLAY INVISIBLE (-4875 4075);
FORCEPROP 0 LAST CDS_SEC 3
J 0
(-4875 4075);
DISPLAY 0.680851 (-4875 4075);
DISPLAY INVISIBLE (-4875 4075);
FORCEPROP 0 LASTPIN (-3775 2250) $PN G35
J 0
(-3765 2260);
DISPLAY 0.680851 (-3765 2260);
PAINT MONO (-3765 2260);
FORCEPROP 0 LASTPIN (-5025 1600) $PN FF5
J 2
(-5035 1610);
DISPLAY 0.680851 (-5035 1610);
PAINT MONO (-5035 1610);
FORCEPROP 0 LASTPIN (-5025 1500) $PN FJ3
J 2
(-5035 1510);
DISPLAY 0.680851 (-5035 1510);
PAINT MONO (-5035 1510);
FORCEPROP 0 LASTPIN (-5025 3500) $PN FJ6
J 2
(-5035 3510);
DISPLAY 0.680851 (-5035 3510);
PAINT MONO (-5035 3510);
FORCEPROP 0 LASTPIN (-5025 3400) $PN FJ23
J 2
(-5035 3410);
DISPLAY 0.680851 (-5035 3410);
PAINT MONO (-5035 3410);
FORCEPROP 0 LASTPIN (-5025 3300) $PN FJ25
J 2
(-5035 3310);
DISPLAY 0.680851 (-5035 3310);
PAINT MONO (-5035 3310);
FORCEPROP 0 LASTPIN (-5025 3200) $PN FJ28
J 2
(-5035 3210);
DISPLAY 0.680851 (-5035 3210);
PAINT MONO (-5035 3210);
FORCEPROP 0 LASTPIN (-3775 1850) $PN FJ31
J 0
(-3765 1860);
DISPLAY 0.680851 (-3765 1860);
PAINT MONO (-3765 1860);
FORCEPROP 0 LASTPIN (-3775 3600) $PN B3
J 0
(-3765 3610);
DISPLAY 0.680851 (-3765 3610);
PAINT MONO (-3765 3610);
FORCEPROP 0 LASTPIN (-3775 3300) $PN B6
J 0
(-3765 3310);
DISPLAY 0.680851 (-3765 3310);
PAINT MONO (-3765 3310);
FORCEPROP 0 LASTPIN (-3775 3500) $PN B9
J 0
(-3765 3510);
DISPLAY 0.680851 (-3765 3510);
PAINT MONO (-3765 3510);
FORCEPROP 0 LASTPIN (-3775 3050) $PN FF8
J 0
(-3765 3060);
DISPLAY 0.680851 (-3765 3060);
PAINT MONO (-3765 3060);
FORCEPROP 0 LASTPIN (-3775 3400) $PN B12
J 0
(-3765 3410);
DISPLAY 0.680851 (-3765 3410);
PAINT MONO (-3765 3410);
FORCEPROP 0 LASTPIN (-3775 3200) $PN E8
J 0
(-3765 3210);
DISPLAY 0.680851 (-3765 3210);
PAINT MONO (-3765 3210);
FORCEPROP 0 LASTPIN (-3775 2750) $PN FJ9
J 0
(-3765 2760);
DISPLAY 0.680851 (-3765 2760);
PAINT MONO (-3765 2760);
FORCEPROP 0 LASTPIN (-3775 2150) $PN F2
J 0
(-3765 2160);
DISPLAY 0.680851 (-3765 2160);
PAINT MONO (-3765 2160);
FORCEPROP 0 LASTPIN (-3775 1000) $PN E18
J 0
(-3765 1010);
DISPLAY 0.680851 (-3765 1010);
PAINT MONO (-3765 1010);
FORCEPROP 0 LASTPIN (-3775 1150) $PN B16
J 0
(-3765 1160);
DISPLAY 0.680851 (-3765 1160);
PAINT MONO (-3765 1160);
FORCEPROP 0 LASTPIN (-5025 1000) $PN FF18
J 2
(-5035 1010);
DISPLAY 0.680851 (-5035 1010);
PAINT MONO (-5035 1010);
FORCEPROP 0 LASTPIN (-5025 1150) $PN FJ16
J 2
(-5035 1160);
DISPLAY 0.680851 (-5035 1160);
PAINT MONO (-5035 1160);
FORCEPROP 0 LASTPIN (-3775 2050) $PN FF11
J 0
(-3765 2060);
DISPLAY 0.680851 (-3765 2060);
PAINT MONO (-3765 2060);
FORCEPROP 0 LASTPIN (-3775 2650) $PN E11
J 0
(-3765 2660);
DISPLAY 0.680851 (-3765 2660);
PAINT MONO (-3765 2660);
FORCEPROP 0 LASTPIN (-3775 2550) $PN FF33
J 0
(-3765 2560);
DISPLAY 0.680851 (-3765 2560);
PAINT MONO (-3765 2560);
FORCEPROP 0 LASTPIN (-5025 2600) $PN F34
J 2
(-5035 2610);
DISPLAY 0.680851 (-5035 2610);
PAINT MONO (-5035 2610);
FORCEPROP 0 LASTPIN (-5025 2500) $PN B23
J 2
(-5035 2510);
DISPLAY 0.680851 (-5035 2510);
PAINT MONO (-5035 2510);
FORCEPROP 0 LASTPIN (-5025 2400) $PN B25
J 2
(-5035 2410);
DISPLAY 0.680851 (-5035 2410);
PAINT MONO (-5035 2410);
FORCEPROP 0 LASTPIN (-5025 2850) $PN B31
J 2
(-5035 2860);
DISPLAY 0.680851 (-5035 2860);
PAINT MONO (-5035 2860);
FORCEPROP 0 LASTPIN (-5025 2750) $PN B28
J 2
(-5035 2760);
DISPLAY 0.680851 (-5035 2760);
PAINT MONO (-5035 2760);
FORCEPROP 0 LASTPIN (-3775 1650) $PN E30
J 0
(-3765 1660);
DISPLAY 0.680851 (-3765 1660);
PAINT MONO (-3765 1660);
FORCEPROP 0 LASTPIN (-5025 2100) $PN FF24
J 2
(-5035 2110);
DISPLAY 0.680851 (-5035 2110);
PAINT MONO (-5035 2110);
FORCEPROP 0 LASTPIN (-5025 2000) $PN FF27
J 2
(-5035 2010);
DISPLAY 0.680851 (-5035 2010);
PAINT MONO (-5035 2010);
FORCEPROP 0 LASTPIN (-5025 1900) $PN FF30
J 2
(-5035 1910);
DISPLAY 0.680851 (-5035 1910);
PAINT MONO (-5035 1910);
FORCEPROP 2 LAST PART_TYPE SMLF
J 0
(-4875 4025);
DISPLAY 0.680851 (-4875 4025);
FORCEPROP 2 LAST VALUE PT5161LRS
J 0
(-4875 3975);
DISPLAY 0.680851 (-4875 3975);
FORCEPROP 1 LAST MATERIAL IC
J 0
(-4875 3775);
DISPLAY 0.723404 (-4875 3775);
PAINT GREEN (-4875 3775);
FORCEPROP 2 LAST CDS_LIB pure_quanta
J 0
(-4375 2300);
DISPLAY INVISIBLE (-4375 2300);
FORCEPROP 1 LAST CDS_LMAN_SYM_OUTLINE -500,1450,450,-1400
J 0
(-4375 2300);
DISPLAY 0.468085 (-4375 2300);
PAINT GREEN (-4375 2300);
DISPLAY INVISIBLE (-4375 2300);
FORCEPROP 1 LAST NEEDS_NO_SIZE TRUE
J 0
(-4375 2300);
DISPLAY 0.723404 (-4375 2300);
PAINT GREEN (-4375 2300);
DISPLAY INVISIBLE (-4375 2300);
FORCEPROP 1 LAST PATH I53
J 0
(-4375 2300);
DISPLAY 0.723404 (-4375 2300);
PAINT GREEN (-4375 2300);
DISPLAY INVISIBLE (-4375 2300);
FORCEPROP 1 LAST PART_NUMBER AJ051610U03
J 0
(-4875 3850);
DISPLAY 0.723404 (-4875 3850);
PAINT GREEN (-4875 3850);
DISPLAY INVISIBLE (-4875 3850);
FORCEADD OFFPAGE..1
(-5975 2400);
FORCEPROP 2 LAST $XR0 277 
J 0
(-6227 2400);
DISPLAY 0.638298 (-6227 2400);
PAINT MONO (-6227 2400);
FORCEPROP 2 LAST CDS_LIB standard
J 0
(-5975 2400);
DISPLAY INVISIBLE (-5975 2400);
FORCEPROP 1 LAST OFFPAGE TRUE
J 0
(-5650 2275);
DISPLAY 0.872340 (-5650 2275);
DISPLAY INVISIBLE (-5650 2275);
FORCEPROP 1 LAST COMMENT_BODY TRUE
J 0
(-5850 2300);
DISPLAY 0.872340 (-5850 2300);
PAINT GREEN (-5850 2300);
DISPLAY INVISIBLE (-5850 2300);
FORCEPROP 2 LAST PATH I54
J 0
(-6225 2450);
DISPLAY 0.680851 (-6225 2450);
DISPLAY INVISIBLE (-6225 2450);
FORCEADD OFFPAGE..1
(-5975 2500);
FORCEPROP 2 LAST $XR0 277 
J 0
(-6227 2500);
DISPLAY 0.638298 (-6227 2500);
PAINT MONO (-6227 2500);
FORCEPROP 2 LAST CDS_LIB standard
J 0
(-5975 2500);
DISPLAY INVISIBLE (-5975 2500);
FORCEPROP 1 LAST OFFPAGE TRUE
J 0
(-5650 2375);
DISPLAY 0.872340 (-5650 2375);
DISPLAY INVISIBLE (-5650 2375);
FORCEPROP 1 LAST COMMENT_BODY TRUE
J 0
(-5850 2400);
DISPLAY 0.872340 (-5850 2400);
PAINT GREEN (-5850 2400);
DISPLAY INVISIBLE (-5850 2400);
FORCEPROP 2 LAST PATH I55
J 0
(-6225 2550);
DISPLAY 0.680851 (-6225 2550);
DISPLAY INVISIBLE (-6225 2550);
FORCEADD OFFPAGE..1
(-5975 2600);
FORCEPROP 2 LAST $XR0 277 
J 0
(-6227 2600);
DISPLAY 0.638298 (-6227 2600);
PAINT MONO (-6227 2600);
FORCEPROP 2 LAST CDS_LIB standard
J 0
(-5975 2600);
DISPLAY INVISIBLE (-5975 2600);
FORCEPROP 1 LAST OFFPAGE TRUE
J 0
(-5650 2475);
DISPLAY 0.872340 (-5650 2475);
DISPLAY INVISIBLE (-5650 2475);
FORCEPROP 1 LAST COMMENT_BODY TRUE
J 0
(-5850 2500);
DISPLAY 0.872340 (-5850 2500);
PAINT GREEN (-5850 2500);
DISPLAY INVISIBLE (-5850 2500);
FORCEPROP 2 LAST PATH I56
J 0
(-6225 2650);
DISPLAY 0.680851 (-6225 2650);
DISPLAY INVISIBLE (-6225 2650);
FORCEADD Q_RES..2
(-8025 4975);
FORCEPROP 1 LAST LOCATION R984
J 0
(-7980 5100);
DISPLAY 0.787234 (-7980 5100);
FORCEPROP 0 LAST $SEC 1
J 0
(-7975 5150);
DISPLAY 0.680851 (-7975 5150);
PAINT MONO (-7975 5150);
DISPLAY INVISIBLE (-7975 5150);
FORCEPROP 0 LAST CDS_SEC 1
J 0
(-7975 5150);
DISPLAY 0.680851 (-7975 5150);
DISPLAY INVISIBLE (-7975 5150);
FORCEPROP 1 LASTPIN (-8025 5075) $PN 1
J 0
(-8020 5037);
DISPLAY 0.787234 (-8020 5037);
PAINT MONO (-8020 5037);
FORCEPROP 1 LASTPIN (-8025 4875) $PN 2
J 0
(-8020 4885);
DISPLAY 0.787234 (-8020 4885);
PAINT MONO (-8020 4885);
FORCEPROP 1 LAST MATERIAL CHIP
J 0
(-7985 4900);
DISPLAY 0.787234 (-7985 4900);
FORCEPROP 1 LAST WATTAGE 1/20W
J 0
(-7985 4950);
DISPLAY 0.787234 (-7985 4950);
FORCEPROP 1 LAST TOLERANCE 5%
J 0
(-7980 5000);
DISPLAY 0.787234 (-7980 5000);
FORCEPROP 1 LAST VALUE 4.7K
J 0
(-7980 5050);
DISPLAY 0.787234 (-7980 5050);
FORCEPROP 1 LAST PACK_TYPE 0201LF
J 0
(-7985 4800);
DISPLAY 0.787234 (-7985 4800);
FORCEPROP 2 LAST CDS_LIB pure_quanta
J 0
(-8025 4975);
DISPLAY INVISIBLE (-8025 4975);
FORCEPROP 1 LAST PATH I57
J 0
(-7975 5150);
DISPLAY 0.978723 (-7975 5150);
PAINT WHITE (-7975 5150);
DISPLAY INVISIBLE (-7975 5150);
FORCEPROP 1 LAST PART_NUMBER CS24701JE04
J 0
(-7985 4850);
DISPLAY 0.978723 (-7985 4850);
DISPLAY INVISIBLE (-7985 4850);
FORCEADD Q_RES..2
(-7725 4975);
FORCEPROP 1 LAST LOCATION R995
J 0
(-7680 5100);
DISPLAY 0.787234 (-7680 5100);
FORCEPROP 0 LAST $SEC 1
J 0
(-7675 5150);
DISPLAY 0.680851 (-7675 5150);
PAINT MONO (-7675 5150);
DISPLAY INVISIBLE (-7675 5150);
FORCEPROP 0 LAST CDS_SEC 1
J 0
(-7675 5150);
DISPLAY 0.680851 (-7675 5150);
DISPLAY INVISIBLE (-7675 5150);
FORCEPROP 1 LASTPIN (-7725 5075) $PN 1
J 0
(-7720 5037);
DISPLAY 0.787234 (-7720 5037);
PAINT MONO (-7720 5037);
FORCEPROP 1 LASTPIN (-7725 4875) $PN 2
J 0
(-7720 4885);
DISPLAY 0.787234 (-7720 4885);
PAINT MONO (-7720 4885);
FORCEPROP 1 LAST MATERIAL CHIP
J 0
(-7685 4900);
DISPLAY 0.787234 (-7685 4900);
FORCEPROP 1 LAST WATTAGE 1/20W
J 0
(-7685 4950);
DISPLAY 0.787234 (-7685 4950);
FORCEPROP 1 LAST TOLERANCE 5%
J 0
(-7680 5000);
DISPLAY 0.787234 (-7680 5000);
FORCEPROP 1 LAST PACK_TYPE 0201LF
J 0
(-7685 4800);
DISPLAY 0.787234 (-7685 4800);
FORCEPROP 1 LAST VALUE 4.7K
J 0
(-7680 5050);
DISPLAY 0.787234 (-7680 5050);
FORCEPROP 2 LAST CDS_LIB pure_quanta
J 0
(-7725 4975);
DISPLAY INVISIBLE (-7725 4975);
FORCEPROP 1 LAST PATH I58
J 0
(-7675 5150);
DISPLAY 0.978723 (-7675 5150);
PAINT WHITE (-7675 5150);
DISPLAY INVISIBLE (-7675 5150);
FORCEPROP 1 LAST PART_NUMBER CS24701JE04
J 0
(-7685 4850);
DISPLAY 0.787234 (-7685 4850);
DISPLAY INVISIBLE (-7685 4850);
FORCEADD UNIVERSAL_GND..1
(-7425 4500);
FORCEPROP 3 LASTPIN (-7425 4550) SIG_NAME GND\g
J 0
(-7415 4560);
DISPLAY 0.659574 (-7415 4560);
PAINT MONO (-7415 4560);
DISPLAY INVISIBLE (-7415 4560);
FORCEPROP 2 LAST CDS_LIB pure_quanta_power
J 0
(-7425 4500);
DISPLAY INVISIBLE (-7425 4500);
FORCEPROP 1 LAST HDL_POWER GND
J 1
(-7400 4425);
DISPLAY 0.872340 (-7400 4425);
PAINT GREEN (-7400 4425);
DISPLAY INVISIBLE (-7400 4425);
FORCEPROP 1 LAST PATH I59
J 0
(-7350 4500);
DISPLAY 0.872340 (-7350 4500);
PAINT AQUA (-7350 4500);
DISPLAY INVISIBLE (-7350 4500);
FORCEADD Q_RES..2
(-7425 4950);
FORCEPROP 1 LAST LOCATION R997
J 0
(-7380 5075);
DISPLAY 0.787234 (-7380 5075);
FORCEPROP 0 LAST $SEC 1
J 0
(-7375 5125);
DISPLAY 0.680851 (-7375 5125);
PAINT MONO (-7375 5125);
DISPLAY INVISIBLE (-7375 5125);
FORCEPROP 0 LAST CDS_SEC 1
J 0
(-7375 5125);
DISPLAY 0.680851 (-7375 5125);
DISPLAY INVISIBLE (-7375 5125);
FORCEPROP 1 LASTPIN (-7425 5050) $PN 1
J 0
(-7420 5012);
DISPLAY 0.787234 (-7420 5012);
PAINT MONO (-7420 5012);
FORCEPROP 1 LASTPIN (-7425 4850) $PN 2
J 0
(-7420 4860);
DISPLAY 0.787234 (-7420 4860);
PAINT MONO (-7420 4860);
FORCEPROP 1 LAST TOLERANCE 5%
J 0
(-7380 4975);
DISPLAY 0.787234 (-7380 4975);
FORCEPROP 1 LAST PACK_TYPE 0201LF
J 0
(-7385 4775);
DISPLAY 0.787234 (-7385 4775);
FORCEPROP 1 LAST WATTAGE 1/20W
J 0
(-7385 4925);
DISPLAY 0.787234 (-7385 4925);
FORCEPROP 1 LAST MATERIAL CHIP
J 0
(-7385 4875);
DISPLAY 0.787234 (-7385 4875);
FORCEPROP 1 LAST VALUE 4.7K
J 0
(-7380 5025);
DISPLAY 0.787234 (-7380 5025);
FORCEPROP 2 LAST CDS_LIB pure_quanta
J 0
(-7425 4950);
DISPLAY INVISIBLE (-7425 4950);
FORCEPROP 1 LAST PATH I60
J 0
(-7375 5125);
DISPLAY 0.978723 (-7375 5125);
PAINT WHITE (-7375 5125);
DISPLAY INVISIBLE (-7375 5125);
FORCEPROP 1 LAST PART_NUMBER CS24701JE04
J 0
(-7385 4825);
DISPLAY 0.638298 (-7385 4825);
DISPLAY INVISIBLE (-7385 4825);
FORCEADD Q_RES..2
(-8025 5900);
FORCEPROP 1 LAST LOCATION R983
J 0
(-7980 6025);
DISPLAY 0.787234 (-7980 6025);
FORCEPROP 0 LAST $SEC 1
J 0
(-7975 6075);
DISPLAY 0.680851 (-7975 6075);
PAINT MONO (-7975 6075);
DISPLAY INVISIBLE (-7975 6075);
FORCEPROP 0 LAST CDS_SEC 1
J 0
(-7975 6075);
DISPLAY 0.680851 (-7975 6075);
DISPLAY INVISIBLE (-7975 6075);
FORCEPROP 1 LASTPIN (-8025 6000) $PN 1
J 0
(-8020 5962);
DISPLAY 0.787234 (-8020 5962);
PAINT MONO (-8020 5962);
FORCEPROP 1 LASTPIN (-8025 5800) $PN 2
J 0
(-8020 5810);
DISPLAY 0.787234 (-8020 5810);
PAINT MONO (-8020 5810);
FORCEPROP 1 LAST PACK_TYPE 0201LF
J 0
(-7975 5750);
DISPLAY 0.787234 (-7975 5750);
FORCEPROP 1 LAST MATERIAL EMPTY
J 0
(-7985 5825);
DISPLAY 0.787234 (-7985 5825);
FORCEPROP 1 LAST VALUE 4.7K
J 0
(-7980 5975);
DISPLAY 0.787234 (-7980 5975);
FORCEPROP 1 LAST TOLERANCE 5%
J 0
(-7980 5925);
DISPLAY 0.787234 (-7980 5925);
FORCEPROP 1 LAST WATTAGE 1/20W
J 0
(-7985 5875);
DISPLAY 0.787234 (-7985 5875);
FORCEPROP 2 LAST CDS_LIB pure_quanta
J 0
(-8025 5900);
DISPLAY INVISIBLE (-8025 5900);
FORCEPROP 1 LAST PATH I61
J 0
(-7975 6075);
DISPLAY 0.978723 (-7975 6075);
PAINT WHITE (-7975 6075);
DISPLAY INVISIBLE (-7975 6075);
FORCEPROP 1 LAST PART_NUMBER CS24701JE04
J 0
(-7985 5775);
DISPLAY 0.978723 (-7985 5775);
DISPLAY INVISIBLE (-7985 5775);
FORCEADD Q_RES..2
(-7725 5925);
FORCEPROP 1 LAST LOCATION R985
J 0
(-7680 6050);
DISPLAY 0.787234 (-7680 6050);
FORCEPROP 0 LAST $SEC 1
J 0
(-7675 6100);
DISPLAY 0.680851 (-7675 6100);
PAINT MONO (-7675 6100);
DISPLAY INVISIBLE (-7675 6100);
FORCEPROP 0 LAST CDS_SEC 1
J 0
(-7675 6100);
DISPLAY 0.680851 (-7675 6100);
DISPLAY INVISIBLE (-7675 6100);
FORCEPROP 1 LASTPIN (-7725 6025) $PN 1
J 0
(-7720 5987);
DISPLAY 0.787234 (-7720 5987);
PAINT MONO (-7720 5987);
FORCEPROP 1 LASTPIN (-7725 5825) $PN 2
J 0
(-7720 5835);
DISPLAY 0.787234 (-7720 5835);
PAINT MONO (-7720 5835);
FORCEPROP 1 LAST WATTAGE 1/20W
J 0
(-7685 5900);
DISPLAY 0.787234 (-7685 5900);
FORCEPROP 1 LAST VALUE 4.7K
J 0
(-7680 6000);
DISPLAY 0.787234 (-7680 6000);
FORCEPROP 1 LAST TOLERANCE 5%
J 0
(-7680 5950);
DISPLAY 0.787234 (-7680 5950);
FORCEPROP 1 LAST PACK_TYPE 0201LF
J 0
(-7685 5750);
DISPLAY 0.787234 (-7685 5750);
FORCEPROP 1 LAST MATERIAL EMPTY
J 0
(-7685 5850);
DISPLAY 0.787234 (-7685 5850);
FORCEPROP 2 LAST CDS_LIB pure_quanta
J 0
(-7725 5925);
DISPLAY INVISIBLE (-7725 5925);
FORCEPROP 1 LAST PATH I62
J 0
(-7675 6100);
DISPLAY 0.978723 (-7675 6100);
PAINT WHITE (-7675 6100);
DISPLAY INVISIBLE (-7675 6100);
FORCEPROP 1 LAST PART_NUMBER CS24701JE04
J 0
(-7685 5800);
DISPLAY 0.787234 (-7685 5800);
DISPLAY INVISIBLE (-7685 5800);
FORCEADD Q_RES..2
(-7425 5950);
FORCEPROP 1 LAST LOCATION R975
J 0
(-7380 6075);
DISPLAY 0.787234 (-7380 6075);
FORCEPROP 0 LAST $SEC 1
J 0
(-7375 6125);
DISPLAY 0.680851 (-7375 6125);
PAINT MONO (-7375 6125);
DISPLAY INVISIBLE (-7375 6125);
FORCEPROP 0 LAST CDS_SEC 1
J 0
(-7375 6125);
DISPLAY 0.680851 (-7375 6125);
DISPLAY INVISIBLE (-7375 6125);
FORCEPROP 1 LASTPIN (-7425 6050) $PN 1
J 0
(-7420 6012);
DISPLAY 0.787234 (-7420 6012);
PAINT MONO (-7420 6012);
FORCEPROP 1 LASTPIN (-7425 5850) $PN 2
J 0
(-7420 5860);
DISPLAY 0.787234 (-7420 5860);
PAINT MONO (-7420 5860);
FORCEPROP 1 LAST WATTAGE 1/20W
J 0
(-7385 5925);
DISPLAY 0.787234 (-7385 5925);
FORCEPROP 1 LAST PACK_TYPE 0201LF
J 0
(-7375 5775);
DISPLAY 0.787234 (-7375 5775);
FORCEPROP 1 LAST MATERIAL EMPTY
J 0
(-7385 5875);
DISPLAY 0.787234 (-7385 5875);
FORCEPROP 1 LAST TOLERANCE 5%
J 0
(-7380 5975);
DISPLAY 0.787234 (-7380 5975);
FORCEPROP 1 LAST VALUE 4.7K
J 0
(-7380 6025);
DISPLAY 0.787234 (-7380 6025);
FORCEPROP 2 LAST CDS_LIB pure_quanta
J 0
(-7425 5950);
DISPLAY INVISIBLE (-7425 5950);
FORCEPROP 1 LAST PATH I63
J 0
(-7375 6125);
DISPLAY 0.978723 (-7375 6125);
PAINT WHITE (-7375 6125);
DISPLAY INVISIBLE (-7375 6125);
FORCEPROP 1 LAST PART_NUMBER CS24701JE04
J 0
(-7375 5825);
DISPLAY 0.638298 (-7375 5825);
DISPLAY INVISIBLE (-7375 5825);
FORCEADD OFFPAGE..5
R 2
(-6375 5350);
FORCEPROP 2 LAST $XR0 277 
J 0
(-6186 5350);
DISPLAY 0.638298 (-6186 5350);
PAINT MONO (-6186 5350);
FORCEPROP 2 LAST CDS_LIB standard
J 0
(-6375 5350);
DISPLAY INVISIBLE (-6375 5350);
FORCEPROP 1 LAST OFFPAGE TRUE
J 2
(-6700 5225);
DISPLAY 0.872340 (-6700 5225);
PAINT GREEN (-6700 5225);
DISPLAY INVISIBLE (-6700 5225);
FORCEPROP 1 LAST COMMENT_BODY TRUE
J 2
(-6475 5275);
DISPLAY 0.872340 (-6475 5275);
PAINT GREEN (-6475 5275);
DISPLAY INVISIBLE (-6475 5275);
FORCEPROP 2 LAST PATH I64
J 0
(-6175 5400);
DISPLAY 0.680851 (-6175 5400);
DISPLAY INVISIBLE (-6175 5400);
FORCEADD OFFPAGE..5
R 2
(-6375 5425);
FORCEPROP 2 LAST $XR0 277 
J 0
(-6186 5425);
DISPLAY 0.638298 (-6186 5425);
PAINT MONO (-6186 5425);
FORCEPROP 2 LAST CDS_LIB standard
J 0
(-6375 5425);
DISPLAY INVISIBLE (-6375 5425);
FORCEPROP 1 LAST OFFPAGE TRUE
J 2
(-6700 5300);
DISPLAY 0.872340 (-6700 5300);
PAINT GREEN (-6700 5300);
DISPLAY INVISIBLE (-6700 5300);
FORCEPROP 1 LAST COMMENT_BODY TRUE
J 2
(-6475 5350);
DISPLAY 0.872340 (-6475 5350);
PAINT GREEN (-6475 5350);
DISPLAY INVISIBLE (-6475 5350);
FORCEPROP 2 LAST PATH I65
J 0
(-6175 5475);
DISPLAY 0.680851 (-6175 5475);
DISPLAY INVISIBLE (-6175 5475);
FORCEADD OFFPAGE..5
R 2
(-6375 5475);
FORCEPROP 2 LAST $XR0 277 
J 0
(-6186 5475);
DISPLAY 0.638298 (-6186 5475);
PAINT MONO (-6186 5475);
FORCEPROP 2 LAST CDS_LIB standard
J 0
(-6375 5475);
DISPLAY INVISIBLE (-6375 5475);
FORCEPROP 1 LAST OFFPAGE TRUE
J 2
(-6700 5350);
DISPLAY 0.872340 (-6700 5350);
PAINT GREEN (-6700 5350);
DISPLAY INVISIBLE (-6700 5350);
FORCEPROP 1 LAST COMMENT_BODY TRUE
J 2
(-6475 5400);
DISPLAY 0.872340 (-6475 5400);
PAINT GREEN (-6475 5400);
DISPLAY INVISIBLE (-6475 5400);
FORCEPROP 2 LAST PATH I66
J 0
(-6175 5525);
DISPLAY 0.680851 (-6175 5525);
DISPLAY INVISIBLE (-6175 5525);
FORCEADD OFFPAGE..5
R 2
(-6375 5525);
FORCEPROP 2 LAST $XR0 277 
J 0
(-6186 5525);
DISPLAY 0.638298 (-6186 5525);
PAINT MONO (-6186 5525);
FORCEPROP 2 LAST CDS_LIB standard
J 0
(-6375 5525);
DISPLAY INVISIBLE (-6375 5525);
FORCEPROP 1 LAST OFFPAGE TRUE
J 2
(-6700 5400);
DISPLAY 0.872340 (-6700 5400);
PAINT GREEN (-6700 5400);
DISPLAY INVISIBLE (-6700 5400);
FORCEPROP 1 LAST COMMENT_BODY TRUE
J 2
(-6475 5450);
DISPLAY 0.872340 (-6475 5450);
PAINT GREEN (-6475 5450);
DISPLAY INVISIBLE (-6475 5450);
FORCEPROP 2 LAST PATH I67
J 0
(-6175 5575);
DISPLAY 0.680851 (-6175 5575);
DISPLAY INVISIBLE (-6175 5575);
FORCEADD OFFPAGE..5
R 2
(-6375 5575);
FORCEPROP 2 LAST $XR0 277 
J 0
(-6186 5575);
DISPLAY 0.638298 (-6186 5575);
PAINT MONO (-6186 5575);
FORCEPROP 2 LAST CDS_LIB standard
J 0
(-6375 5575);
DISPLAY INVISIBLE (-6375 5575);
FORCEPROP 1 LAST OFFPAGE TRUE
J 2
(-6700 5450);
DISPLAY 0.872340 (-6700 5450);
PAINT GREEN (-6700 5450);
DISPLAY INVISIBLE (-6700 5450);
FORCEPROP 1 LAST COMMENT_BODY TRUE
J 2
(-6475 5500);
DISPLAY 0.872340 (-6475 5500);
PAINT GREEN (-6475 5500);
DISPLAY INVISIBLE (-6475 5500);
FORCEPROP 2 LAST PATH I68
J 0
(-6175 5625);
DISPLAY 0.680851 (-6175 5625);
DISPLAY INVISIBLE (-6175 5625);
FORCEADD OFFPAGE..5
R 2
(-6375 5650);
FORCEPROP 2 LAST $XR0 277 
J 0
(-6186 5650);
DISPLAY 0.638298 (-6186 5650);
PAINT MONO (-6186 5650);
FORCEPROP 2 LAST CDS_LIB standard
J 0
(-6375 5650);
DISPLAY INVISIBLE (-6375 5650);
FORCEPROP 1 LAST OFFPAGE TRUE
J 2
(-6700 5525);
DISPLAY 0.872340 (-6700 5525);
PAINT GREEN (-6700 5525);
DISPLAY INVISIBLE (-6700 5525);
FORCEPROP 1 LAST COMMENT_BODY TRUE
J 2
(-6475 5575);
DISPLAY 0.872340 (-6475 5575);
PAINT GREEN (-6475 5575);
DISPLAY INVISIBLE (-6475 5575);
FORCEPROP 2 LAST PATH I69
J 0
(-6175 5700);
DISPLAY 0.680851 (-6175 5700);
DISPLAY INVISIBLE (-6175 5700);
FORCEADD UNIVERSAL_GND..1
(-5025 5150);
FORCEPROP 3 LASTPIN (-5025 5200) SIG_NAME GND\g
J 0
(-5015 5210);
DISPLAY 0.659574 (-5015 5210);
PAINT MONO (-5015 5210);
DISPLAY INVISIBLE (-5015 5210);
FORCEPROP 2 LAST CDS_LIB pure_quanta_power
J 0
(-5025 5150);
DISPLAY INVISIBLE (-5025 5150);
FORCEPROP 1 LAST HDL_POWER GND
J 1
(-5000 5075);
DISPLAY 0.872340 (-5000 5075);
PAINT GREEN (-5000 5075);
DISPLAY INVISIBLE (-5000 5075);
FORCEPROP 1 LAST PATH I70
J 0
(-4950 5150);
DISPLAY 0.872340 (-4950 5150);
PAINT AQUA (-4950 5150);
DISPLAY INVISIBLE (-4950 5150);
FORCEADD Q_RES..2
(-5025 5500);
FORCEPROP 1 LAST LOCATION R1001
J 0
(-4980 5625);
DISPLAY 0.787234 (-4980 5625);
FORCEPROP 0 LAST $SEC 1
J 0
(-4975 5675);
DISPLAY 0.680851 (-4975 5675);
PAINT MONO (-4975 5675);
DISPLAY INVISIBLE (-4975 5675);
FORCEPROP 0 LAST CDS_SEC 1
J 0
(-4975 5675);
DISPLAY 0.680851 (-4975 5675);
DISPLAY INVISIBLE (-4975 5675);
FORCEPROP 1 LASTPIN (-5025 5600) $PN 1
J 0
(-5020 5562);
DISPLAY 0.787234 (-5020 5562);
PAINT MONO (-5020 5562);
FORCEPROP 1 LASTPIN (-5025 5400) $PN 2
J 0
(-5020 5410);
DISPLAY 0.787234 (-5020 5410);
PAINT MONO (-5020 5410);
FORCEPROP 1 LAST TOLERANCE 5%
J 0
(-4980 5525);
DISPLAY 0.787234 (-4980 5525);
FORCEPROP 1 LAST WATTAGE 1/20W
J 0
(-4985 5475);
DISPLAY 0.787234 (-4985 5475);
FORCEPROP 1 LAST VALUE 4.7K
J 0
(-4980 5575);
DISPLAY 0.787234 (-4980 5575);
FORCEPROP 1 LAST PACK_TYPE 0201LF
J 0
(-4985 5325);
DISPLAY 0.787234 (-4985 5325);
FORCEPROP 1 LAST MATERIAL EMPTY
J 0
(-4985 5425);
DISPLAY 0.787234 (-4985 5425);
FORCEPROP 2 LAST CDS_LIB pure_quanta
J 0
(-5025 5500);
DISPLAY INVISIBLE (-5025 5500);
FORCEPROP 1 LAST PATH I71
J 0
(-4975 5675);
DISPLAY 0.978723 (-4975 5675);
PAINT WHITE (-4975 5675);
DISPLAY INVISIBLE (-4975 5675);
FORCEPROP 1 LAST PART_NUMBER CS24701JE04
J 0
(-4985 5375);
DISPLAY 0.787234 (-4985 5375);
DISPLAY INVISIBLE (-4985 5375);
FORCEADD Q_RES..2
(-5025 6025);
FORCEPROP 1 LAST LOCATION R998
J 0
(-4980 6150);
DISPLAY 0.787234 (-4980 6150);
FORCEPROP 0 LAST $SEC 1
J 0
(-4975 6200);
DISPLAY 0.680851 (-4975 6200);
PAINT MONO (-4975 6200);
DISPLAY INVISIBLE (-4975 6200);
FORCEPROP 0 LAST CDS_SEC 1
J 0
(-4975 6200);
DISPLAY 0.680851 (-4975 6200);
DISPLAY INVISIBLE (-4975 6200);
FORCEPROP 1 LASTPIN (-5025 6125) $PN 1
J 0
(-5020 6087);
DISPLAY 0.787234 (-5020 6087);
PAINT MONO (-5020 6087);
FORCEPROP 1 LASTPIN (-5025 5925) $PN 2
J 0
(-5020 5935);
DISPLAY 0.787234 (-5020 5935);
PAINT MONO (-5020 5935);
FORCEPROP 1 LAST PACK_TYPE 0201LF
J 0
(-4985 5850);
DISPLAY 0.787234 (-4985 5850);
FORCEPROP 1 LAST MATERIAL CHIP
J 0
(-4985 5950);
DISPLAY 0.787234 (-4985 5950);
FORCEPROP 1 LAST VALUE 4.7K
J 0
(-4980 6100);
DISPLAY 0.787234 (-4980 6100);
FORCEPROP 1 LAST TOLERANCE 5%
J 0
(-4980 6050);
DISPLAY 0.787234 (-4980 6050);
FORCEPROP 1 LAST WATTAGE 1/20W
J 0
(-4985 6000);
DISPLAY 0.787234 (-4985 6000);
FORCEPROP 2 LAST CDS_LIB pure_quanta
J 0
(-5025 6025);
DISPLAY INVISIBLE (-5025 6025);
FORCEPROP 1 LAST PATH I72
J 0
(-4975 6200);
DISPLAY 0.978723 (-4975 6200);
PAINT WHITE (-4975 6200);
DISPLAY INVISIBLE (-4975 6200);
FORCEPROP 1 LAST PART_NUMBER CS24701JE04
J 0
(-4985 5900);
DISPLAY 0.787234 (-4985 5900);
DISPLAY INVISIBLE (-4985 5900);
FORCEADD OFFPAGE..5
R 2
(-4150 5750);
FORCEPROP 2 LAST $XR0 277 
J 0
(-3961 5750);
DISPLAY 0.638298 (-3961 5750);
PAINT MONO (-3961 5750);
FORCEPROP 2 LAST CDS_LIB standard
J 0
(-4150 5750);
DISPLAY INVISIBLE (-4150 5750);
FORCEPROP 1 LAST OFFPAGE TRUE
J 2
(-4475 5625);
DISPLAY 0.872340 (-4475 5625);
PAINT GREEN (-4475 5625);
DISPLAY INVISIBLE (-4475 5625);
FORCEPROP 1 LAST COMMENT_BODY TRUE
J 2
(-4250 5675);
DISPLAY 0.872340 (-4250 5675);
PAINT GREEN (-4250 5675);
DISPLAY INVISIBLE (-4250 5675);
FORCEPROP 2 LAST PATH I73
J 0
(-3950 5800);
DISPLAY 0.680851 (-3950 5800);
DISPLAY INVISIBLE (-3950 5800);
FORCEADD P1V0..1
(-5025 6350);
FORCEPROP 3 LASTPIN (-5025 6300) SIG_NAME P1V8_CPU0_RT_1D\g
J 0
(-5015 6310);
DISPLAY 0.659574 (-5015 6310);
PAINT MONO (-5015 6310);
DISPLAY INVISIBLE (-5015 6310);
FORCEPROP 1 LAST HDL_POWER P1V8_CPU0_RT_1D
J 1
(-5025 6400);
DISPLAY 0.489362 (-5025 6400);
PAINT SKYBLUE (-5025 6400);
FORCEPROP 2 LAST CDS_LIB pure_quanta_power
J 0
(-5025 6350);
DISPLAY INVISIBLE (-5025 6350);
FORCEPROP 1 LAST PATH I74
J 0
(-4975 6375);
DISPLAY 0.872340 (-4975 6375);
PAINT AQUA (-4975 6375);
DISPLAY INVISIBLE (-4975 6375);
FORCEADD UNIVERSAL_GND..1
R 1
(-3375 1650);
FORCEPROP 3 LASTPIN (-3425 1650) SIG_NAME GND\g
J 0
(-3415 1660);
DISPLAY 0.659574 (-3415 1660);
PAINT MONO (-3415 1660);
DISPLAY INVISIBLE (-3415 1660);
FORCEPROP 2 LAST CDS_LIB pure_quanta_power
J 0
(-3375 1650);
DISPLAY INVISIBLE (-3375 1650);
FORCEPROP 1 LAST HDL_POWER GND
R 1
J 1
(-3300 1675);
DISPLAY 0.872340 (-3300 1675);
PAINT GREEN (-3300 1675);
DISPLAY INVISIBLE (-3300 1675);
FORCEPROP 1 LAST PATH I75
R 1
J 0
(-3375 1725);
DISPLAY 0.872340 (-3375 1725);
PAINT AQUA (-3375 1725);
DISPLAY INVISIBLE (-3375 1725);
FORCEADD Q_RES..1
(-2575 2150);
FORCEPROP 1 LAST LOCATION R953
J 0
(-2850 2150);
DISPLAY 0.978723 (-2850 2150);
FORCEPROP 2 LAST SEC 1
J 0
(-2625 2350);
DISPLAY 0.680851 (-2625 2350);
PAINT MONO (-2625 2350);
DISPLAY INVISIBLE (-2625 2350);
FORCEPROP 1 LASTPIN (-2675 2150) $PN 1
J 0
(-2663 2162);
DISPLAY 0.787234 (-2663 2162);
PAINT MONO (-2663 2162);
FORCEPROP 1 LASTPIN (-2475 2150) $PN 2
J 0
(-2513 2162);
DISPLAY 0.787234 (-2513 2162);
PAINT MONO (-2513 2162);
FORCEPROP 1 LAST VALUE 0
J 2
(-2375 2150);
DISPLAY 0.787234 (-2375 2150);
FORCEPROP 1 LAST PACK_TYPE 0201LF
J 0
(-2275 2150);
DISPLAY 0.787234 (-2275 2150);
FORCEPROP 1 LAST WATTAGE 1/20W
J 2
(-2775 2225);
DISPLAY 0.787234 (-2775 2225);
DISPLAY INVISIBLE (-2775 2225);
FORCEPROP 1 LAST TOLERANCE 5%
J 0
(-2750 2275);
DISPLAY 0.787234 (-2750 2275);
DISPLAY INVISIBLE (-2750 2275);
FORCEPROP 1 LAST MATERIAL CHIP
J 0
(-2750 2225);
DISPLAY 0.787234 (-2750 2225);
DISPLAY INVISIBLE (-2750 2225);
FORCEPROP 2 LAST SEC_TYPE 0201LF
J 0
(-2625 2350);
DISPLAY 0.680851 (-2625 2350);
DISPLAY INVISIBLE (-2625 2350);
FORCEPROP 2 LAST CDS_LIB pure_quanta
J 0
(-2575 2150);
DISPLAY INVISIBLE (-2575 2150);
FORCEPROP 1 LAST PATH I76
J 0
(-2625 2300);
DISPLAY 0.978723 (-2625 2300);
PAINT WHITE (-2625 2300);
DISPLAY INVISIBLE (-2625 2300);
FORCEPROP 1 LAST PART_NUMBER CS00001JE10
J 0
(-2625 2275);
DISPLAY 0.808511 (-2625 2275);
DISPLAY INVISIBLE (-2625 2275);
FORCEADD Q_RES..1
(-2575 2050);
FORCEPROP 1 LAST LOCATION R963
J 0
(-2850 2050);
DISPLAY 0.978723 (-2850 2050);
FORCEPROP 0 LAST $SEC 1
J 0
(-2275 2100);
DISPLAY 0.680851 (-2275 2100);
PAINT MONO (-2275 2100);
DISPLAY INVISIBLE (-2275 2100);
FORCEPROP 0 LAST CDS_SEC 1
J 0
(-2275 2100);
DISPLAY 0.680851 (-2275 2100);
DISPLAY INVISIBLE (-2275 2100);
FORCEPROP 1 LASTPIN (-2675 2050) $PN 1
J 0
(-2663 2062);
DISPLAY 0.787234 (-2663 2062);
PAINT MONO (-2663 2062);
FORCEPROP 1 LASTPIN (-2475 2050) $PN 2
J 0
(-2513 2062);
DISPLAY 0.787234 (-2513 2062);
PAINT MONO (-2513 2062);
FORCEPROP 1 LAST VALUE 0
J 2
(-2375 2050);
DISPLAY 0.787234 (-2375 2050);
FORCEPROP 1 LAST PACK_TYPE 0201LF
J 0
(-2275 2050);
DISPLAY 0.787234 (-2275 2050);
FORCEPROP 2 LAST CDS_LIB pure_quanta
J 0
(-2575 2050);
DISPLAY INVISIBLE (-2575 2050);
FORCEPROP 1 LAST MATERIAL CHIP
J 0
(-2750 2125);
DISPLAY 0.787234 (-2750 2125);
DISPLAY INVISIBLE (-2750 2125);
FORCEPROP 1 LAST TOLERANCE 5%
J 0
(-2750 2175);
DISPLAY 0.787234 (-2750 2175);
DISPLAY INVISIBLE (-2750 2175);
FORCEPROP 1 LAST WATTAGE 1/20W
J 2
(-2775 2125);
DISPLAY 0.787234 (-2775 2125);
DISPLAY INVISIBLE (-2775 2125);
FORCEPROP 1 LAST PATH I77
J 0
(-2625 2200);
DISPLAY 0.978723 (-2625 2200);
PAINT WHITE (-2625 2200);
DISPLAY INVISIBLE (-2625 2200);
FORCEPROP 1 LAST PART_NUMBER CS00001JE10
J 0
(-2625 2175);
DISPLAY 0.808511 (-2625 2175);
DISPLAY INVISIBLE (-2625 2175);
FORCEADD OFFPAGE..1
R 2
(-2375 2550);
FORCEPROP 2 LAST $XR0 277 
J 0
(-2189 2550);
DISPLAY 0.638298 (-2189 2550);
PAINT MONO (-2189 2550);
FORCEPROP 2 LAST CDS_LIB standard
J 0
(-2375 2550);
DISPLAY INVISIBLE (-2375 2550);
FORCEPROP 1 LAST OFFPAGE TRUE
J 2
(-2700 2425);
DISPLAY 0.872340 (-2700 2425);
DISPLAY INVISIBLE (-2700 2425);
FORCEPROP 1 LAST COMMENT_BODY TRUE
J 2
(-2500 2450);
DISPLAY 0.872340 (-2500 2450);
PAINT GREEN (-2500 2450);
DISPLAY INVISIBLE (-2500 2450);
FORCEPROP 2 LAST PATH I79
J 0
(-2175 2600);
DISPLAY 0.680851 (-2175 2600);
DISPLAY INVISIBLE (-2175 2600);
FORCEADD OFFPAGE..1
R 2
(-2400 2750);
FORCEPROP 2 LAST $XR0 277 
J 0
(-2214 2750);
DISPLAY 0.638298 (-2214 2750);
PAINT MONO (-2214 2750);
FORCEPROP 2 LAST CDS_LIB standard
J 2
(-2400 2750);
DISPLAY INVISIBLE (-2400 2750);
FORCEPROP 1 LAST OFFPAGE TRUE
J 2
(-2725 2625);
DISPLAY 0.872340 (-2725 2625);
DISPLAY INVISIBLE (-2725 2625);
FORCEPROP 1 LAST COMMENT_BODY TRUE
J 2
(-2525 2650);
DISPLAY 0.872340 (-2525 2650);
PAINT GREEN (-2525 2650);
DISPLAY INVISIBLE (-2525 2650);
FORCEPROP 2 LAST PATH I80
J 0
(-2200 2800);
DISPLAY 0.680851 (-2200 2800);
DISPLAY INVISIBLE (-2200 2800);
FORCEADD OFFPAGE..1
R 2
(-2475 3050);
FORCEPROP 2 LAST $XR0 277 
J 0
(-2289 3050);
DISPLAY 0.638298 (-2289 3050);
PAINT MONO (-2289 3050);
FORCEPROP 2 LAST CDS_LIB standard
J 0
(-2475 3050);
DISPLAY INVISIBLE (-2475 3050);
FORCEPROP 1 LAST OFFPAGE TRUE
J 2
(-2800 2925);
DISPLAY 0.872340 (-2800 2925);
DISPLAY INVISIBLE (-2800 2925);
FORCEPROP 1 LAST COMMENT_BODY TRUE
J 2
(-2600 2950);
DISPLAY 0.872340 (-2600 2950);
PAINT GREEN (-2600 2950);
DISPLAY INVISIBLE (-2600 2950);
FORCEPROP 2 LAST PATH I82
J 0
(-2275 3100);
DISPLAY 0.680851 (-2275 3100);
DISPLAY INVISIBLE (-2275 3100);
FORCEADD OFFPAGE..1
R 2
(-1050 2050);
FORCEPROP 2 LAST $XR1 277 
J 0
(-774 2050);
DISPLAY 0.638298 (-774 2050);
PAINT MONO (-774 2050);
FORCEPROP 2 LAST $XR0 81 
J 0
(-864 2050);
DISPLAY 0.638298 (-864 2050);
PAINT MONO (-864 2050);
FORCEPROP 2 LAST CDS_LIB standard
J 0
(-1050 2050);
DISPLAY INVISIBLE (-1050 2050);
FORCEPROP 1 LAST OFFPAGE TRUE
J 2
(-1375 1925);
DISPLAY 0.872340 (-1375 1925);
DISPLAY INVISIBLE (-1375 1925);
FORCEPROP 1 LAST COMMENT_BODY TRUE
J 2
(-1175 1950);
DISPLAY 0.872340 (-1175 1950);
PAINT GREEN (-1175 1950);
DISPLAY INVISIBLE (-1175 1950);
FORCEPROP 2 LAST PATH I83
J 0
(-750 2100);
DISPLAY 0.680851 (-750 2100);
DISPLAY INVISIBLE (-750 2100);
FORCEADD OFFPAGE..1
R 2
(-1050 2150);
FORCEPROP 2 LAST $XR1 277 
J 0
(-774 2150);
DISPLAY 0.638298 (-774 2150);
PAINT MONO (-774 2150);
FORCEPROP 2 LAST $XR0 81 
J 0
(-864 2150);
DISPLAY 0.638298 (-864 2150);
PAINT MONO (-864 2150);
FORCEPROP 2 LAST CDS_LIB standard
J 0
(-1050 2150);
DISPLAY INVISIBLE (-1050 2150);
FORCEPROP 1 LAST OFFPAGE TRUE
J 2
(-1375 2025);
DISPLAY 0.872340 (-1375 2025);
DISPLAY INVISIBLE (-1375 2025);
FORCEPROP 1 LAST COMMENT_BODY TRUE
J 2
(-1175 2050);
DISPLAY 0.872340 (-1175 2050);
PAINT GREEN (-1175 2050);
DISPLAY INVISIBLE (-1175 2050);
FORCEPROP 2 LAST PATH I84
J 0
(-750 2200);
DISPLAY 0.680851 (-750 2200);
DISPLAY INVISIBLE (-750 2200);
FORCEADD UNIVERSAL_GND..1
(-3475 4750);
FORCEPROP 3 LASTPIN (-3475 4800) SIG_NAME GND\g
J 0
(-3465 4810);
DISPLAY 0.659574 (-3465 4810);
PAINT MONO (-3465 4810);
DISPLAY INVISIBLE (-3465 4810);
FORCEPROP 2 LAST CDS_LIB pure_quanta_power
J 0
(-3475 4750);
DISPLAY INVISIBLE (-3475 4750);
FORCEPROP 1 LAST HDL_POWER GND
J 1
(-3450 4675);
DISPLAY 0.872340 (-3450 4675);
PAINT GREEN (-3450 4675);
DISPLAY INVISIBLE (-3450 4675);
FORCEPROP 1 LAST PATH I85
J 0
(-3400 4750);
DISPLAY 0.872340 (-3400 4750);
PAINT AQUA (-3400 4750);
DISPLAY INVISIBLE (-3400 4750);
FORCEADD Q_RES..2
(-3475 5175);
FORCEPROP 1 LAST LOCATION R965
J 0
(-3430 5300);
DISPLAY 0.787234 (-3430 5300);
FORCEPROP 0 LAST $SEC 1
J 0
(-3425 5350);
DISPLAY 0.680851 (-3425 5350);
PAINT MONO (-3425 5350);
DISPLAY INVISIBLE (-3425 5350);
FORCEPROP 0 LAST CDS_SEC 1
J 0
(-3425 5350);
DISPLAY 0.680851 (-3425 5350);
DISPLAY INVISIBLE (-3425 5350);
FORCEPROP 1 LASTPIN (-3475 5275) $PN 1
J 0
(-3470 5237);
DISPLAY 0.787234 (-3470 5237);
PAINT MONO (-3470 5237);
FORCEPROP 1 LASTPIN (-3475 5075) $PN 2
J 0
(-3470 5085);
DISPLAY 0.787234 (-3470 5085);
PAINT MONO (-3470 5085);
FORCEPROP 1 LAST PACK_TYPE 0201LF
J 0
(-3435 5000);
DISPLAY 0.787234 (-3435 5000);
FORCEPROP 1 LAST MATERIAL EMPTY
J 0
(-3435 5100);
DISPLAY 0.787234 (-3435 5100);
FORCEPROP 1 LAST WATTAGE 1/20W
J 0
(-3435 5150);
DISPLAY 0.787234 (-3435 5150);
FORCEPROP 1 LAST VALUE 1K
J 0
(-3430 5250);
DISPLAY 0.787234 (-3430 5250);
FORCEPROP 1 LAST TOLERANCE 1%
J 0
(-3430 5200);
DISPLAY 0.787234 (-3430 5200);
FORCEPROP 2 LAST CDS_LIB pure_quanta
J 0
(-3475 5175);
DISPLAY INVISIBLE (-3475 5175);
FORCEPROP 1 LAST PATH I86
J 0
(-3425 5350);
DISPLAY 0.978723 (-3425 5350);
PAINT WHITE (-3425 5350);
DISPLAY INVISIBLE (-3425 5350);
FORCEPROP 1 LAST PART_NUMBER CS21001FE07
J 0
(-3435 5050);
DISPLAY 0.978723 (-3435 5050);
DISPLAY INVISIBLE (-3435 5050);
FORCEADD Q_RES..2
(-3175 5175);
FORCEPROP 1 LAST LOCATION R967
J 0
(-3130 5300);
DISPLAY 0.787234 (-3130 5300);
FORCEPROP 0 LAST $SEC 1
J 0
(-3125 5350);
DISPLAY 0.680851 (-3125 5350);
PAINT MONO (-3125 5350);
DISPLAY INVISIBLE (-3125 5350);
FORCEPROP 0 LAST CDS_SEC 1
J 0
(-3125 5350);
DISPLAY 0.680851 (-3125 5350);
DISPLAY INVISIBLE (-3125 5350);
FORCEPROP 1 LASTPIN (-3175 5275) $PN 1
J 0
(-3170 5237);
DISPLAY 0.787234 (-3170 5237);
PAINT MONO (-3170 5237);
FORCEPROP 1 LASTPIN (-3175 5075) $PN 2
J 0
(-3170 5085);
DISPLAY 0.787234 (-3170 5085);
PAINT MONO (-3170 5085);
FORCEPROP 1 LAST MATERIAL CHIP
J 0
(-3135 5100);
DISPLAY 0.787234 (-3135 5100);
FORCEPROP 1 LAST VALUE 20K
J 0
(-3130 5250);
DISPLAY 0.787234 (-3130 5250);
FORCEPROP 1 LAST PACK_TYPE 0201LF
J 0
(-3135 5000);
DISPLAY 0.787234 (-3135 5000);
FORCEPROP 1 LAST TOLERANCE 1%
J 0
(-3130 5200);
DISPLAY 0.787234 (-3130 5200);
FORCEPROP 1 LAST WATTAGE 1/20W
J 0
(-3135 5150);
DISPLAY 0.787234 (-3135 5150);
FORCEPROP 2 LAST CDS_LIB pure_quanta
J 0
(-3175 5175);
DISPLAY INVISIBLE (-3175 5175);
FORCEPROP 1 LAST PATH I87
J 0
(-3125 5350);
DISPLAY 0.978723 (-3125 5350);
PAINT WHITE (-3125 5350);
DISPLAY INVISIBLE (-3125 5350);
FORCEPROP 1 LAST PART_NUMBER CS32001FE00
J 0
(-3135 5050);
DISPLAY 0.978723 (-3135 5050);
DISPLAY INVISIBLE (-3135 5050);
FORCEADD Q_RES..2
(-3475 5950);
FORCEPROP 1 LAST LOCATION R964
J 0
(-3430 6075);
DISPLAY 0.787234 (-3430 6075);
FORCEPROP 0 LAST $SEC 1
J 0
(-3425 6125);
DISPLAY 0.680851 (-3425 6125);
PAINT MONO (-3425 6125);
DISPLAY INVISIBLE (-3425 6125);
FORCEPROP 0 LAST CDS_SEC 1
J 0
(-3425 6125);
DISPLAY 0.680851 (-3425 6125);
DISPLAY INVISIBLE (-3425 6125);
FORCEPROP 1 LASTPIN (-3475 6050) $PN 1
J 0
(-3470 6012);
DISPLAY 0.787234 (-3470 6012);
PAINT MONO (-3470 6012);
FORCEPROP 1 LASTPIN (-3475 5850) $PN 2
J 0
(-3470 5860);
DISPLAY 0.787234 (-3470 5860);
PAINT MONO (-3470 5860);
FORCEPROP 1 LAST VALUE 1K
J 0
(-3430 6025);
DISPLAY 0.787234 (-3430 6025);
FORCEPROP 1 LAST MATERIAL CHIP
J 0
(-3435 5875);
DISPLAY 0.787234 (-3435 5875);
FORCEPROP 1 LAST WATTAGE 1/20W
J 0
(-3435 5925);
DISPLAY 0.787234 (-3435 5925);
FORCEPROP 1 LAST TOLERANCE 1%
J 0
(-3430 5975);
DISPLAY 0.787234 (-3430 5975);
FORCEPROP 1 LAST PACK_TYPE 0201LF
J 0
(-3435 5775);
DISPLAY 0.787234 (-3435 5775);
FORCEPROP 2 LAST CDS_LIB pure_quanta
J 0
(-3475 5950);
DISPLAY INVISIBLE (-3475 5950);
FORCEPROP 1 LAST PATH I88
J 0
(-3425 6125);
DISPLAY 0.978723 (-3425 6125);
PAINT WHITE (-3425 6125);
DISPLAY INVISIBLE (-3425 6125);
FORCEPROP 1 LAST PART_NUMBER CS21001FE07
J 0
(-3435 5825);
DISPLAY 0.978723 (-3435 5825);
DISPLAY INVISIBLE (-3435 5825);
FORCEADD Q_RES..2
(-3175 5950);
FORCEPROP 1 LAST LOCATION R966
J 0
(-3130 6075);
DISPLAY 0.978723 (-3130 6075);
FORCEPROP 0 LAST $SEC 1
J 0
(-3125 6125);
DISPLAY 0.680851 (-3125 6125);
PAINT MONO (-3125 6125);
DISPLAY INVISIBLE (-3125 6125);
FORCEPROP 0 LAST CDS_SEC 1
J 0
(-3125 6125);
DISPLAY 0.680851 (-3125 6125);
DISPLAY INVISIBLE (-3125 6125);
FORCEPROP 1 LASTPIN (-3175 6050) $PN 1
J 0
(-3170 6012);
DISPLAY 0.787234 (-3170 6012);
PAINT MONO (-3170 6012);
FORCEPROP 1 LASTPIN (-3175 5850) $PN 2
J 0
(-3170 5860);
DISPLAY 0.787234 (-3170 5860);
PAINT MONO (-3170 5860);
FORCEPROP 1 LAST WATTAGE 1/20W
J 0
(-3135 5925);
DISPLAY 0.787234 (-3135 5925);
FORCEPROP 1 LAST VALUE 1K
J 0
(-3130 6025);
DISPLAY 0.787234 (-3130 6025);
FORCEPROP 1 LAST MATERIAL EMPTY
J 0
(-3135 5875);
DISPLAY 0.787234 (-3135 5875);
FORCEPROP 1 LAST TOLERANCE 1%
J 0
(-3130 5975);
DISPLAY 0.787234 (-3130 5975);
FORCEPROP 1 LAST PACK_TYPE 0201LF
J 0
(-3135 5775);
DISPLAY 0.787234 (-3135 5775);
FORCEPROP 2 LAST CDS_LIB pure_quanta
J 0
(-3175 5950);
DISPLAY INVISIBLE (-3175 5950);
FORCEPROP 1 LAST PATH I89
J 0
(-3125 6125);
DISPLAY 0.978723 (-3125 6125);
PAINT WHITE (-3125 6125);
DISPLAY INVISIBLE (-3125 6125);
FORCEPROP 1 LAST PART_NUMBER CS21001FE07
J 0
(-3135 5825);
DISPLAY 0.978723 (-3135 5825);
DISPLAY INVISIBLE (-3135 5825);
FORCEADD Q_RES..2
(-2825 5175);
FORCEPROP 1 LAST LOCATION R969
J 0
(-2780 5300);
DISPLAY 0.978723 (-2780 5300);
FORCEPROP 0 LAST $SEC 1
J 0
(-2775 5350);
DISPLAY 0.680851 (-2775 5350);
PAINT MONO (-2775 5350);
DISPLAY INVISIBLE (-2775 5350);
FORCEPROP 0 LAST CDS_SEC 1
J 0
(-2775 5350);
DISPLAY 0.680851 (-2775 5350);
DISPLAY INVISIBLE (-2775 5350);
FORCEPROP 1 LASTPIN (-2825 5275) $PN 1
J 0
(-2820 5237);
DISPLAY 0.787234 (-2820 5237);
PAINT MONO (-2820 5237);
FORCEPROP 1 LASTPIN (-2825 5075) $PN 2
J 0
(-2820 5085);
DISPLAY 0.787234 (-2820 5085);
PAINT MONO (-2820 5085);
FORCEPROP 1 LAST WATTAGE 1/20W
J 0
(-2785 5150);
DISPLAY 0.787234 (-2785 5150);
FORCEPROP 1 LAST MATERIAL CHIP
J 0
(-2785 5100);
DISPLAY 0.787234 (-2785 5100);
FORCEPROP 1 LAST PACK_TYPE 0201LF
J 0
(-2785 5000);
DISPLAY 0.787234 (-2785 5000);
FORCEPROP 1 LAST TOLERANCE 1%
J 0
(-2780 5200);
DISPLAY 0.787234 (-2780 5200);
FORCEPROP 1 LAST VALUE 1K
J 0
(-2780 5250);
DISPLAY 0.787234 (-2780 5250);
FORCEPROP 2 LAST CDS_LIB pure_quanta
J 0
(-2825 5175);
DISPLAY INVISIBLE (-2825 5175);
FORCEPROP 1 LAST PATH I90
J 0
(-2775 5350);
DISPLAY 0.978723 (-2775 5350);
PAINT WHITE (-2775 5350);
DISPLAY INVISIBLE (-2775 5350);
FORCEPROP 1 LAST PART_NUMBER CS21001FE07
J 0
(-2785 5050);
DISPLAY 0.978723 (-2785 5050);
DISPLAY INVISIBLE (-2785 5050);
FORCEADD Q_RES..2
(-2825 5925);
FORCEPROP 1 LAST LOCATION R968
J 0
(-2780 6050);
DISPLAY 0.978723 (-2780 6050);
FORCEPROP 0 LAST $SEC 1
J 0
(-2775 6100);
DISPLAY 0.680851 (-2775 6100);
PAINT MONO (-2775 6100);
DISPLAY INVISIBLE (-2775 6100);
FORCEPROP 0 LAST CDS_SEC 1
J 0
(-2775 6100);
DISPLAY 0.680851 (-2775 6100);
DISPLAY INVISIBLE (-2775 6100);
FORCEPROP 1 LASTPIN (-2825 6025) $PN 1
J 0
(-2820 5987);
DISPLAY 0.787234 (-2820 5987);
PAINT MONO (-2820 5987);
FORCEPROP 1 LASTPIN (-2825 5825) $PN 2
J 0
(-2820 5835);
DISPLAY 0.787234 (-2820 5835);
PAINT MONO (-2820 5835);
FORCEPROP 1 LAST WATTAGE 1/20W
J 0
(-2785 5900);
DISPLAY 0.787234 (-2785 5900);
FORCEPROP 1 LAST PACK_TYPE 0201LF
J 0
(-2785 5750);
DISPLAY 0.787234 (-2785 5750);
FORCEPROP 1 LAST VALUE 1K
J 0
(-2780 6000);
DISPLAY 0.787234 (-2780 6000);
FORCEPROP 1 LAST TOLERANCE 1%
J 0
(-2780 5950);
DISPLAY 0.787234 (-2780 5950);
FORCEPROP 1 LAST MATERIAL EMPTY
J 0
(-2785 5850);
DISPLAY 0.787234 (-2785 5850);
FORCEPROP 2 LAST CDS_LIB pure_quanta
J 0
(-2825 5925);
DISPLAY INVISIBLE (-2825 5925);
FORCEPROP 1 LAST PATH I91
J 0
(-2775 6100);
DISPLAY 0.978723 (-2775 6100);
PAINT WHITE (-2775 6100);
DISPLAY INVISIBLE (-2775 6100);
FORCEPROP 1 LAST PART_NUMBER CS21001FE07
J 0
(-2785 5800);
DISPLAY 0.978723 (-2785 5800);
DISPLAY INVISIBLE (-2785 5800);
FORCEADD P1V0..1
(-3475 6375);
FORCEPROP 3 LASTPIN (-3475 6325) SIG_NAME P1V8_CPU0_RT_1D\g
J 0
(-3465 6335);
DISPLAY 0.659574 (-3465 6335);
PAINT MONO (-3465 6335);
DISPLAY INVISIBLE (-3465 6335);
FORCEPROP 1 LAST HDL_POWER P1V8_CPU0_RT_1D
J 1
(-3475 6425);
DISPLAY 0.489362 (-3475 6425);
PAINT SKYBLUE (-3475 6425);
FORCEPROP 2 LAST CDS_LIB pure_quanta_power
J 0
(-3475 6375);
DISPLAY INVISIBLE (-3475 6375);
FORCEPROP 1 LAST PATH I92
J 0
(-3425 6400);
DISPLAY 0.872340 (-3425 6400);
PAINT AQUA (-3425 6400);
DISPLAY INVISIBLE (-3425 6400);
FORCEADD GND..1
(-1475 4800);
FORCEPROP 3 LASTPIN (-1475 4850) SIG_NAME GND\g
J 0
(-1465 4860);
DISPLAY 0.659574 (-1465 4860);
PAINT MONO (-1465 4860);
DISPLAY INVISIBLE (-1465 4860);
FORCEPROP 1 LAST SIZE 1B
J 0
(-1400 4750);
DISPLAY 0.851064 (-1400 4750);
PAINT GREEN (-1400 4750);
DISPLAY INVISIBLE (-1400 4750);
FORCEPROP 2 LAST BOM_COST MEM
J 0
(-1575 4875);
DISPLAY 0.808511 (-1575 4875);
DISPLAY INVISIBLE (-1575 4875);
FORCEPROP 2 LAST CDS_LIB pure_quanta_power
J 0
(-1475 4800);
DISPLAY INVISIBLE (-1475 4800);
FORCEPROP 1 LAST HDL_POWER GND
J 0
(-1475 4950);
DISPLAY 0.851064 (-1475 4950);
PAINT GREEN (-1475 4950);
DISPLAY INVISIBLE (-1475 4950);
FORCEPROP 1 LAST PATH I93
J 0
(-1400 4800);
DISPLAY 0.872340 (-1400 4800);
PAINT AQUA (-1400 4800);
DISPLAY INVISIBLE (-1400 4800);
FORCEADD GND..1
(-1300 4825);
FORCEPROP 3 LASTPIN (-1300 4875) SIG_NAME GND\g
J 0
(-1290 4885);
DISPLAY 0.659574 (-1290 4885);
PAINT MONO (-1290 4885);
DISPLAY INVISIBLE (-1290 4885);
FORCEPROP 1 LAST SIZE 1B
J 0
(-1225 4775);
DISPLAY 0.851064 (-1225 4775);
PAINT GREEN (-1225 4775);
DISPLAY INVISIBLE (-1225 4775);
FORCEPROP 2 LAST BOM_COST MEM
J 0
(-1400 4900);
DISPLAY 0.808511 (-1400 4900);
DISPLAY INVISIBLE (-1400 4900);
FORCEPROP 2 LAST CDS_LIB pure_quanta_power
J 0
(-1300 4825);
DISPLAY INVISIBLE (-1300 4825);
FORCEPROP 1 LAST HDL_POWER GND
J 0
(-1300 4975);
DISPLAY 0.851064 (-1300 4975);
PAINT GREEN (-1300 4975);
DISPLAY INVISIBLE (-1300 4975);
FORCEPROP 1 LAST PATH I94
J 0
(-1225 4825);
DISPLAY 0.872340 (-1225 4825);
PAINT AQUA (-1225 4825);
DISPLAY INVISIBLE (-1225 4825);
FORCEADD OFFPAGE..5
R 2
(-1925 5425);
FORCEPROP 2 LAST $XR0 277 
J 0
(-1736 5425);
DISPLAY 0.638298 (-1736 5425);
PAINT MONO (-1736 5425);
FORCEPROP 2 LAST CDS_LIB standard
J 0
(-1925 5425);
DISPLAY INVISIBLE (-1925 5425);
FORCEPROP 1 LAST OFFPAGE TRUE
J 2
(-2250 5300);
DISPLAY 0.872340 (-2250 5300);
PAINT GREEN (-2250 5300);
DISPLAY INVISIBLE (-2250 5300);
FORCEPROP 1 LAST COMMENT_BODY TRUE
J 2
(-2025 5350);
DISPLAY 0.872340 (-2025 5350);
PAINT GREEN (-2025 5350);
DISPLAY INVISIBLE (-2025 5350);
FORCEPROP 2 LAST PATH I95
J 0
(-1725 5475);
DISPLAY 0.680851 (-1725 5475);
DISPLAY INVISIBLE (-1725 5475);
FORCEADD Q_RES..2
R 2
(-1475 5175);
FORCEPROP 1 LAST LOCATION R971
J 2
(-1520 5300);
DISPLAY 0.638298 (-1520 5300);
FORCEPROP 0 LAST $SEC 1
J 0
(-1500 5350);
DISPLAY 0.680851 (-1500 5350);
PAINT MONO (-1500 5350);
DISPLAY INVISIBLE (-1500 5350);
FORCEPROP 0 LAST CDS_SEC 1
J 0
(-1500 5350);
DISPLAY 0.680851 (-1500 5350);
DISPLAY INVISIBLE (-1500 5350);
FORCEPROP 1 LASTPIN (-1475 5275) $PN 1
J 2
(-1480 5237);
DISPLAY 0.787234 (-1480 5237);
PAINT MONO (-1480 5237);
FORCEPROP 1 LASTPIN (-1475 5075) $PN 2
J 2
(-1480 5085);
DISPLAY 0.787234 (-1480 5085);
PAINT MONO (-1480 5085);
FORCEPROP 1 LAST VALUE 10K
J 2
(-1520 5250);
DISPLAY 0.638298 (-1520 5250);
FORCEPROP 1 LAST TOLERANCE 1%
J 2
(-1520 5200);
DISPLAY 0.638298 (-1520 5200);
FORCEPROP 1 LAST MATERIAL CHIP
J 2
(-1515 5100);
DISPLAY 0.638298 (-1515 5100);
FORCEPROP 1 LAST WATTAGE 1/20W
J 2
(-1515 5150);
DISPLAY 0.638298 (-1515 5150);
FORCEPROP 1 LAST PACK_TYPE 0201LF
J 2
(-1515 5000);
DISPLAY 0.638298 (-1515 5000);
FORCEPROP 2 LAST CDS_LIB pure_quanta
J 2
(-1475 5175);
DISPLAY INVISIBLE (-1475 5175);
FORCEPROP 1 LAST PATH I96
J 2
(-1525 5350);
DISPLAY 0.978723 (-1525 5350);
PAINT WHITE (-1525 5350);
DISPLAY INVISIBLE (-1525 5350);
FORCEPROP 1 LAST PART_NUMBER CS31001FE17
J 2
(-1515 5050);
DISPLAY 0.638298 (-1515 5050);
DISPLAY INVISIBLE (-1515 5050);
FORCEADD Q_RES..2
(-1300 5175);
FORCEPROP 1 LAST LOCATION R970
J 0
(-1255 5300);
DISPLAY 0.638298 (-1255 5300);
FORCEPROP 0 LAST $SEC 1
J 0
(-1250 5350);
DISPLAY 0.680851 (-1250 5350);
PAINT MONO (-1250 5350);
DISPLAY INVISIBLE (-1250 5350);
FORCEPROP 0 LAST CDS_SEC 1
J 0
(-1250 5350);
DISPLAY 0.680851 (-1250 5350);
DISPLAY INVISIBLE (-1250 5350);
FORCEPROP 1 LASTPIN (-1300 5275) $PN 1
J 0
(-1295 5237);
DISPLAY 0.787234 (-1295 5237);
PAINT MONO (-1295 5237);
FORCEPROP 1 LASTPIN (-1300 5075) $PN 2
J 0
(-1295 5085);
DISPLAY 0.787234 (-1295 5085);
PAINT MONO (-1295 5085);
FORCEPROP 1 LAST PACK_TYPE 0201LF
J 0
(-1260 5000);
DISPLAY 0.638298 (-1260 5000);
FORCEPROP 1 LAST MATERIAL CHIP
J 0
(-1260 5100);
DISPLAY 0.638298 (-1260 5100);
FORCEPROP 1 LAST WATTAGE 1/20W
J 0
(-1260 5150);
DISPLAY 0.638298 (-1260 5150);
FORCEPROP 1 LAST VALUE 10K
J 0
(-1255 5250);
DISPLAY 0.638298 (-1255 5250);
FORCEPROP 1 LAST TOLERANCE 1%
J 0
(-1255 5200);
DISPLAY 0.638298 (-1255 5200);
FORCEPROP 2 LAST CDS_LIB pure_quanta
J 0
(-1300 5175);
DISPLAY INVISIBLE (-1300 5175);
FORCEPROP 1 LAST PATH I97
J 0
(-1250 5350);
DISPLAY 0.978723 (-1250 5350);
PAINT WHITE (-1250 5350);
DISPLAY INVISIBLE (-1250 5350);
FORCEPROP 1 LAST PART_NUMBER CS31001FE17
J 0
(-1260 5050);
DISPLAY 0.638298 (-1260 5050);
DISPLAY INVISIBLE (-1260 5050);
FORCEADD Q_RES..2
R 2
(-1475 6000);
FORCEPROP 1 LAST LOCATION R974
J 2
(-1520 6125);
DISPLAY 0.787234 (-1520 6125);
FORCEPROP 0 LAST $SEC 1
J 0
(-1500 6175);
DISPLAY 0.680851 (-1500 6175);
PAINT MONO (-1500 6175);
DISPLAY INVISIBLE (-1500 6175);
FORCEPROP 0 LAST CDS_SEC 1
J 0
(-1500 6175);
DISPLAY 0.680851 (-1500 6175);
DISPLAY INVISIBLE (-1500 6175);
FORCEPROP 1 LASTPIN (-1475 6100) $PN 1
J 2
(-1480 6062);
DISPLAY 0.787234 (-1480 6062);
PAINT MONO (-1480 6062);
FORCEPROP 1 LASTPIN (-1475 5900) $PN 2
J 2
(-1480 5910);
DISPLAY 0.787234 (-1480 5910);
PAINT MONO (-1480 5910);
FORCEPROP 1 LAST MATERIAL EMPTY
J 2
(-1515 5925);
DISPLAY 0.787234 (-1515 5925);
FORCEPROP 1 LAST WATTAGE 1/20W
J 2
(-1515 5975);
DISPLAY 0.787234 (-1515 5975);
FORCEPROP 1 LAST VALUE 4.7K
J 2
(-1520 6075);
DISPLAY 0.787234 (-1520 6075);
FORCEPROP 1 LAST TOLERANCE 5%
J 2
(-1520 6025);
DISPLAY 0.787234 (-1520 6025);
FORCEPROP 1 LAST PACK_TYPE 0201LF
J 2
(-1525 5850);
DISPLAY 0.787234 (-1525 5850);
FORCEPROP 2 LAST CDS_LIB pure_quanta
J 2
(-1475 6000);
DISPLAY INVISIBLE (-1475 6000);
FORCEPROP 1 LAST PATH I98
J 2
(-1525 6175);
DISPLAY 0.978723 (-1525 6175);
PAINT WHITE (-1525 6175);
DISPLAY INVISIBLE (-1525 6175);
FORCEPROP 1 LAST PART_NUMBER CS24701JE04
J 2
(-1515 5875);
DISPLAY 0.978723 (-1515 5875);
DISPLAY INVISIBLE (-1515 5875);
FORCEADD OFFPAGE..1
R 2
(-500 5550);
FORCEPROP 2 LAST $XR1 277 
J 0
(-224 5550);
DISPLAY 0.638298 (-224 5550);
PAINT MONO (-224 5550);
FORCEPROP 2 LAST $XR0 81 
J 0
(-314 5550);
DISPLAY 0.638298 (-314 5550);
PAINT MONO (-314 5550);
FORCEPROP 2 LAST CDS_LIB standard
J 0
(-500 5550);
DISPLAY INVISIBLE (-500 5550);
FORCEPROP 1 LAST OFFPAGE TRUE
J 2
(-825 5425);
DISPLAY 0.872340 (-825 5425);
PAINT GREEN (-825 5425);
DISPLAY INVISIBLE (-825 5425);
FORCEPROP 1 LAST COMMENT_BODY TRUE
J 2
(-625 5450);
DISPLAY 0.872340 (-625 5450);
PAINT GREEN (-625 5450);
DISPLAY INVISIBLE (-625 5450);
FORCEPROP 2 LAST PATH I99
J 0
(-200 5600);
DISPLAY 0.680851 (-200 5600);
DISPLAY INVISIBLE (-200 5600);
FORCEADD DNS..1
(-1275 3875);
PAINT RED (-1275 3875);
FORCEPROP 2 LAST CDS_LIB mstr_misc
J 0
(-1275 3875);
DISPLAY INVISIBLE (-1275 3875);
FORCEPROP 1 LAST COMMENT_BODY TRUE
R 1
J 0
(-1200 3650);
DISPLAY 0.872340 (-1200 3650);
PAINT GREEN (-1200 3650);
DISPLAY INVISIBLE (-1200 3650);
FORCEADD QUANTA_TITLE_BLOCK_C..1
(0 0);
FORCEPROP 0 LAST CDS_CON_LAST_MODIFIED Thu Sep 14 16:13:07 2023
J 0
(-1885 15);
DISPLAY INVISIBLE (-1885 15);
FORCEPROP 1 LAST CUSTOM_TXT_CDS <CON_LAST_MODIFIED>
J 0
(-1885 15);
DISPLAY 0.978723 (-1885 15);
FORCEPROP 2 LAST CUSTOM_TXT_CDS <XR_PAGE_TITLE>
J 0
(-7890 5250);
DISPLAY 0.638298 (-7890 5250);
PAINT PINK (-7890 5250);
DISPLAY INVISIBLE (-7890 5250);
FORCEPROP 1 LAST CUSTOM_TXT_CDS <NAME_2>
J 0
(-3175 50);
FORCEPROP 1 LAST CUSTOM_TXT_CDS <NAME_1>
J 0
(-3175 175);
FORCEPROP 1 LAST CUSTOM_TXT_CDS <Q_NUMBER>
J 0
(-1403 103);
DISPLAY 1.212766 (-1403 103);
FORCEPROP 1 LAST CUSTOM_TXT_CDS <Q_PROJ>
J 0
(-2382 102);
DISPLAY 1.212766 (-2382 102);
FORCEPROP 1 LAST CUSTOM_TXT_CDS <Q_REV>
J 0
(-184 103);
DISPLAY 1.212766 (-184 103);
FORCEPROP 1 LAST CUSTOM_TXT_CDS <CON_PAGE_NUM> OF <CON_TOTAL_PAGES>
J 0
(-446 18);
DISPLAY 0.978723 (-446 18);
FORCEPROP 1 LAST Q_TITLE RETIMER_CPU0_P0(5)
J 0
(-9366 26);
DISPLAY 2.446809 (-9366 26);
PAINT GREEN (-9366 26);
FORCEPROP 2 LAST PAGE_BORDER TRUE
J 0
(-7890 5250);
DISPLAY 0.638298 (-7890 5250);
PAINT PINK (-7890 5250);
DISPLAY INVISIBLE (-7890 5250);
FORCEPROP 1 LAST CDS_LMAN_SYM_OUTLINE -9475,6775,100,-125
J 0
(0 0);
DISPLAY 0.468085 (0 0);
PAINT GREEN (0 0);
DISPLAY INVISIBLE (0 0);
FORCEPROP 2 LAST CDS_LIB pure_quanta
J 0
(0 0);
DISPLAY INVISIBLE (0 0);
FORCEPROP 2 LAST CDS_XR_PAGE_TITLE CR-277 : @T6G_MB_LIB.T6G(SCH_1):PAGE277
J 0
(-7890 5250);
DISPLAY 0.638298 (-7890 5250);
PAINT PINK (-7890 5250);
DISPLAY INVISIBLE (-7890 5250);
FORCEPROP 1 LAST Q_DEPT BU9
J 1
(-3763 49);
DISPLAY 1.957447 (-3763 49);
PAINT GREEN (-3763 49);
DISPLAY INVISIBLE (-3763 49);
FORCEPROP 1 LAST COMMENT_BODY TRUE
J 0
(12 -13);
DISPLAY 0.978723 (12 -13);
PAINT GREEN (12 -13);
DISPLAY INVISIBLE (12 -13);
FORCEADD DNS..1
(-6425 675);
PAINT RED (-6425 675);
FORCEPROP 2 LAST CDS_LIB mstr_misc
J 0
(-6425 675);
DISPLAY INVISIBLE (-6425 675);
FORCEPROP 1 LAST COMMENT_BODY TRUE
R 1
J 0
(-6350 450);
DISPLAY 0.872340 (-6350 450);
PAINT GREEN (-6350 450);
DISPLAY INVISIBLE (-6350 450);
FORCEADD DNS..1
(-8925 4050);
PAINT RED (-8925 4050);
FORCEPROP 2 LAST CDS_LIB mstr_misc
J 0
(-8925 4050);
DISPLAY INVISIBLE (-8925 4050);
FORCEPROP 1 LAST COMMENT_BODY TRUE
R 1
J 0
(-8850 3825);
DISPLAY 0.872340 (-8850 3825);
PAINT GREEN (-8850 3825);
DISPLAY INVISIBLE (-8850 3825);
FORCEADD DNS..1
(-8825 5925);
PAINT RED (-8825 5925);
FORCEPROP 2 LAST CDS_LIB mstr_misc
J 0
(-8825 5925);
DISPLAY INVISIBLE (-8825 5925);
FORCEPROP 1 LAST COMMENT_BODY TRUE
R 1
J 0
(-8750 5700);
DISPLAY 0.872340 (-8750 5700);
PAINT GREEN (-8750 5700);
DISPLAY INVISIBLE (-8750 5700);
FORCEADD DNS..1
(-8225 5950);
PAINT RED (-8225 5950);
FORCEPROP 2 LAST CDS_LIB mstr_misc
J 0
(-8225 5950);
DISPLAY INVISIBLE (-8225 5950);
FORCEPROP 1 LAST COMMENT_BODY TRUE
R 1
J 0
(-8150 5725);
DISPLAY 0.872340 (-8150 5725);
PAINT GREEN (-8150 5725);
DISPLAY INVISIBLE (-8150 5725);
FORCEADD DNS..1
(-7925 5925);
PAINT RED (-7925 5925);
FORCEPROP 2 LAST CDS_LIB mstr_misc
J 0
(-7925 5925);
DISPLAY INVISIBLE (-7925 5925);
FORCEPROP 1 LAST COMMENT_BODY TRUE
R 1
J 0
(-7850 5700);
DISPLAY 0.872340 (-7850 5700);
PAINT GREEN (-7850 5700);
DISPLAY INVISIBLE (-7850 5700);
FORCEADD DNS..1
(-7650 5975);
PAINT RED (-7650 5975);
FORCEPROP 2 LAST CDS_LIB mstr_misc
J 0
(-7650 5975);
DISPLAY INVISIBLE (-7650 5975);
FORCEPROP 1 LAST COMMENT_BODY TRUE
R 1
J 0
(-7575 5750);
DISPLAY 0.872340 (-7575 5750);
PAINT GREEN (-7575 5750);
DISPLAY INVISIBLE (-7575 5750);
FORCEADD DNS..1
(-7325 5925);
PAINT RED (-7325 5925);
FORCEPROP 2 LAST CDS_LIB mstr_misc
J 0
(-7325 5925);
DISPLAY INVISIBLE (-7325 5925);
FORCEPROP 1 LAST COMMENT_BODY TRUE
R 1
J 0
(-7250 5700);
DISPLAY 0.872340 (-7250 5700);
PAINT GREEN (-7250 5700);
DISPLAY INVISIBLE (-7250 5700);
FORCEADD DNS..1
(-6075 700);
PAINT RED (-6075 700);
FORCEPROP 2 LAST CDS_LIB mstr_misc
J 0
(-6075 700);
DISPLAY INVISIBLE (-6075 700);
FORCEPROP 1 LAST COMMENT_BODY TRUE
R 1
J 0
(-6000 475);
DISPLAY 0.872340 (-6000 475);
PAINT GREEN (-6000 475);
DISPLAY INVISIBLE (-6000 475);
FORCEADD DNS..1
(-4950 5450);
PAINT RED (-4950 5450);
FORCEPROP 2 LAST CDS_LIB mstr_misc
J 0
(-4950 5450);
DISPLAY INVISIBLE (-4950 5450);
FORCEPROP 1 LAST COMMENT_BODY TRUE
R 1
J 0
(-4875 5225);
DISPLAY 0.872340 (-4875 5225);
PAINT GREEN (-4875 5225);
DISPLAY INVISIBLE (-4875 5225);
FORCEADD DNS..1
(-3425 5150);
PAINT RED (-3425 5150);
FORCEPROP 2 LAST CDS_LIB mstr_misc
J 0
(-3425 5150);
DISPLAY INVISIBLE (-3425 5150);
FORCEPROP 1 LAST COMMENT_BODY TRUE
R 1
J 0
(-3350 4925);
DISPLAY 0.872340 (-3350 4925);
PAINT GREEN (-3350 4925);
DISPLAY INVISIBLE (-3350 4925);
FORCEADD DNS..1
(-3125 5975);
PAINT RED (-3125 5975);
FORCEPROP 2 LAST CDS_LIB mstr_misc
J 0
(-3125 5975);
DISPLAY INVISIBLE (-3125 5975);
FORCEPROP 1 LAST COMMENT_BODY TRUE
R 1
J 0
(-3050 5750);
DISPLAY 0.872340 (-3050 5750);
PAINT GREEN (-3050 5750);
DISPLAY INVISIBLE (-3050 5750);
FORCEADD DNS..1
(-2775 5950);
PAINT RED (-2775 5950);
FORCEPROP 2 LAST CDS_LIB mstr_misc
J 0
(-2775 5950);
DISPLAY INVISIBLE (-2775 5950);
FORCEPROP 1 LAST COMMENT_BODY TRUE
R 1
J 0
(-2700 5725);
DISPLAY 0.872340 (-2700 5725);
PAINT GREEN (-2700 5725);
DISPLAY INVISIBLE (-2700 5725);
FORCEADD DNS..1
(-1475 6025);
PAINT RED (-1475 6025);
FORCEPROP 2 LAST CDS_LIB mstr_misc
J 0
(-1475 6025);
DISPLAY INVISIBLE (-1475 6025);
FORCEPROP 1 LAST COMMENT_BODY TRUE
R 1
J 0
(-1400 5800);
DISPLAY 0.872340 (-1400 5800);
PAINT GREEN (-1400 5800);
DISPLAY INVISIBLE (-1400 5800);
FORCEADD DNS..1
(-575 1475);
PAINT RED (-575 1475);
FORCEPROP 2 LAST CDS_LIB mstr_misc
J 0
(-575 1475);
DISPLAY INVISIBLE (-575 1475);
FORCEPROP 1 LAST COMMENT_BODY TRUE
R 1
J 0
(-500 1250);
DISPLAY 0.872340 (-500 1250);
PAINT GREEN (-500 1250);
DISPLAY INVISIBLE (-500 1250);
FORCEADD DNS..1
(-850 1475);
PAINT RED (-850 1475);
FORCEPROP 2 LAST CDS_LIB mstr_misc
J 0
(-850 1475);
DISPLAY INVISIBLE (-850 1475);
FORCEPROP 1 LAST COMMENT_BODY TRUE
R 1
J 0
(-775 1250);
DISPLAY 0.872340 (-775 1250);
PAINT GREEN (-775 1250);
DISPLAY INVISIBLE (-775 1250);
FORCEADD DNS..1
(-1150 1450);
PAINT RED (-1150 1450);
FORCEPROP 2 LAST CDS_LIB mstr_misc
J 0
(-1150 1450);
DISPLAY INVISIBLE (-1150 1450);
FORCEPROP 1 LAST COMMENT_BODY TRUE
R 1
J 0
(-1075 1225);
DISPLAY 0.872340 (-1075 1225);
PAINT GREEN (-1075 1225);
DISPLAY INVISIBLE (-1075 1225);
FORCEADD DNS..1
(-1450 1500);
PAINT RED (-1450 1500);
FORCEPROP 2 LAST CDS_LIB mstr_misc
J 0
(-1450 1500);
DISPLAY INVISIBLE (-1450 1500);
FORCEPROP 1 LAST COMMENT_BODY TRUE
R 1
J 0
(-1375 1275);
DISPLAY 0.872340 (-1375 1275);
PAINT GREEN (-1375 1275);
DISPLAY INVISIBLE (-1375 1275);
WIRE 16 -1 (-1475 6200)(-1475 6100);
WIRE 16 -1 (-2600 3200)(-2000 3200);
WIRE 16 -1 (-1350 3250)(-1350 3000);
WIRE 16 -1 (-1350 3975)(-1350 4225);
WIRE 16 -1 (-2575 2250)(-2000 2250);
WIRE 16 -1 (-650 725)(-650 575);
WIRE 16 -1 (-8975 3300)(-8975 3175);
WIRE 16 -1 (-8975 4175)(-8975 4350);
WIRE 16 -1 (-6300 575)(-6300 400);
WIRE 16 -1 (-6150 575)(-6150 400);
WIRE 16 -1 (-5025 5400)(-5025 5200);
WIRE 16 -1 (-5025 6125)(-5025 6300);
WIRE 16 -1 (-3775 1650)(-3425 1650);
WIRE 16 -1 (-1475 5075)(-1475 4850);
WIRE 16 -1 (-1300 5075)(-1300 4875);
WIRE 16 -1 (-6425 1600)(-7700 1600);
FORCEPROP 2 LAST SIG_NAME SMB_RT_CPU0_P0_ROM_MUX_1D_SCL
J 0
(-7610 1610);
DISPLAY 0.680851 (-7610 1610);
PAINT SKYBLUE (-7610 1610);
WIRE 16 -1 (-5025 1600)(-6225 1600);
FORCEPROP 2 LAST SIG_NAME SMB_RT_CPU0_P0_ROM_MUX_1D_R_SCL
J 0
(-6160 1625);
DISPLAY 0.680851 (-6160 1625);
PAINT SKYBLUE (-6160 1625);
FORCEPROP 2 LASTPROP $XRERR UNIQUE?
J 0
(-6400 1625);
DISPLAY 0.638298 (-6400 1625);
PAINT MONO (-6400 1625);
DISPLAY INVISIBLE (-6400 1625);
WIRE 16 -1 (-6425 1500)(-7700 1500);
FORCEPROP 2 LAST SIG_NAME SMB_RT_CPU0_P0_ROM_MUX_1D_SDA
J 0
(-7635 1510);
DISPLAY 0.680851 (-7635 1510);
PAINT SKYBLUE (-7635 1510);
WIRE 16 -1 (-5025 1500)(-6225 1500);
FORCEPROP 2 LAST SIG_NAME SMB_RT_CPU0_P0_ROM_MUX_1D_R_SDA
J 0
(-6185 1525);
DISPLAY 0.680851 (-6185 1525);
PAINT SKYBLUE (-6185 1525);
FORCEPROP 2 LASTPROP $XRERR UNIQUE?
J 0
(-6425 1525);
DISPLAY 0.638298 (-6425 1525);
PAINT MONO (-6425 1525);
DISPLAY INVISIBLE (-6425 1525);
WIRE 16 -1 (-7850 3850)(-8975 3850);
FORCEPROP 2 LAST SIG_NAME RT_CPU0_P0_SCAN_MODE
J 0
(-8585 3860);
DISPLAY 0.680851 (-8585 3860);
PAINT SKYBLUE (-8585 3860);
WIRE 16 -1 (-8975 3975)(-8975 3850);
WIRE 16 -1 (-8975 3850)(-8975 3500);
WIRE 16 -1 (-925 1550)(-925 1700);
WIRE 16 -1 (-925 1700)(-650 1700);
WIRE 16 -1 (-1200 1700)(-925 1700);
WIRE 16 -1 (-1200 1550)(-1200 1700);
WIRE 16 -1 (-1475 1700)(-1200 1700);
WIRE 16 -1 (-650 1575)(-650 1700);
WIRE 16 -1 (-650 1700)(-650 1725);
WIRE 16 -1 (-1475 1550)(-1475 1700);
WIRE 16 -1 (-1200 1350)(-1200 1100);
WIRE 16 -1 (-2575 1100)(-1200 1100);
FORCEPROP 2 LAST SIG_NAME JTAG_TMS_RT_CPU0_P0
J 0
(-2385 1110);
DISPLAY 0.680851 (-2385 1110);
PAINT WHITE (-2385 1110);
WIRE 16 -1 (-1475 1350)(-1475 1050);
WIRE 16 -1 (-2575 1050)(-1475 1050);
FORCEPROP 2 LAST SIG_NAME JTAG_TDI_RT_CPU0_P0
J 0
(-2410 1060);
DISPLAY 0.680851 (-2410 1060);
PAINT WHITE (-2410 1060);
WIRE 16 -1 (-650 1375)(-650 1200);
WIRE 16 -1 (-650 1200)(-650 925);
WIRE 16 -1 (-2575 1200)(-650 1200);
FORCEPROP 2 LAST SIG_NAME JTAG_TCK_RT_CPU0_P0
J 0
(-2410 1210);
DISPLAY 0.680851 (-2410 1210);
PAINT WHITE (-2410 1210);
WIRE 16 -1 (-925 1350)(-925 1150);
WIRE 16 -1 (-2575 1150)(-925 1150);
FORCEPROP 2 LAST SIG_NAME JTAG_TDO_RT_CPU0_P0
J 0
(-2385 1160);
DISPLAY 0.680851 (-2385 1160);
PAINT WHITE (-2385 1160);
WIRE 16 -1 (-2475 2050)(-1100 2050);
FORCEPROP 2 LAST SIG_NAME RST_RT_CPU0_P0_RESET_R_N
J 0
(-1960 2060);
DISPLAY 0.680851 (-1960 2060);
PAINT SKYBLUE (-1960 2060);
WIRE 16 -1 (-3775 3500)(-2775 3500);
FORCEPROP 2 LAST SIG_NAME JTAG_TDO_RT_CPU0_P0
J 0
(-3585 3510);
DISPLAY 0.680851 (-3585 3510);
PAINT WHITE (-3585 3510);
WIRE 16 -1 (-3775 3600)(-2775 3600);
FORCEPROP 2 LAST SIG_NAME JTAG_TCK_RT_CPU0_P0
J 0
(-3610 3610);
DISPLAY 0.680851 (-3610 3610);
PAINT WHITE (-3610 3610);
WIRE 16 -1 (-3775 3200)(-2800 3200);
FORCEPROP 2 LAST SIG_NAME JTAG_TRST_RT_CPU0_P0_N
J 0
(-3610 3210);
DISPLAY 0.680851 (-3610 3210);
PAINT WHITE (-3610 3210);
FORCEPROP 2 LASTPROP $XRERR UNIQUE?
J 0
(-3850 3210);
DISPLAY 0.638298 (-3850 3210);
PAINT MONO (-3850 3210);
DISPLAY INVISIBLE (-3850 3210);
WIRE 16 -1 (-3775 3300)(-2775 3300);
FORCEPROP 2 LAST SIG_NAME JTAG_TDI_RT_CPU0_P0
J 0
(-3610 3310);
DISPLAY 0.680851 (-3610 3310);
PAINT WHITE (-3610 3310);
WIRE 16 -1 (-3775 3400)(-2775 3400);
FORCEPROP 2 LAST SIG_NAME JTAG_TMS_RT_CPU0_P0
J 0
(-3585 3410);
DISPLAY 0.680851 (-3585 3410);
PAINT WHITE (-3585 3410);
WIRE 16 -1 (-5025 3200)(-5975 3200);
FORCEPROP 2 LAST SIG_NAME GPIO3_RT_CPU0_P0
J 0
(-5835 3210);
DISPLAY 0.680851 (-5835 3210);
PAINT SKYBLUE (-5835 3210);
WIRE 16 -1 (-3775 2050)(-2675 2050);
FORCEPROP 2 LAST SIG_NAME RST_RT_CPU0_P0_RESET_N
J 0
(-3585 2060);
DISPLAY 0.680851 (-3585 2060);
PAINT SKYBLUE (-3585 2060);
FORCEPROP 2 LASTPROP $XRERR UNIQUE?
J 0
(-3825 2060);
DISPLAY 0.638298 (-3825 2060);
PAINT MONO (-3825 2060);
DISPLAY INVISIBLE (-3825 2060);
WIRE 16 -1 (-8950 6250)(-8325 6250);
WIRE 16 -1 (-8950 6300)(-8950 6250);
WIRE 16 -1 (-8950 6250)(-8950 6050);
WIRE 16 -1 (-8025 6250)(-8325 6250);
WIRE 16 -1 (-8325 6250)(-8325 6050);
WIRE 16 -1 (-7725 6250)(-8025 6250);
WIRE 16 -1 (-8025 6250)(-8025 6000);
WIRE 16 -1 (-7725 6250)(-7425 6250);
WIRE 16 -1 (-7725 6250)(-7725 6025);
WIRE 16 -1 (-7425 6250)(-7425 6050);
WIRE 16 -1 (-7725 4875)(-7725 4675);
WIRE 16 -1 (-7725 4675)(-7425 4675);
WIRE 16 -1 (-7725 4675)(-8025 4675);
WIRE 16 -1 (-8025 4875)(-8025 4675);
WIRE 16 -1 (-8025 4675)(-8325 4675);
WIRE 16 -1 (-7425 4850)(-7425 4675);
WIRE 16 -1 (-7425 4675)(-7425 4550);
WIRE 16 -1 (-8325 4900)(-8325 4675);
WIRE 16 -1 (-8650 4675)(-8325 4675);
WIRE 16 -1 (-8650 4900)(-8650 4675);
WIRE 16 -1 (-8950 4675)(-8650 4675);
WIRE 16 -1 (-8950 4900)(-8950 4675);
WIRE 16 -1 (-2825 5075)(-2825 4900);
WIRE 16 -1 (-2825 4900)(-3175 4900);
WIRE 16 -1 (-3175 5075)(-3175 4900);
WIRE 16 -1 (-3175 4900)(-3475 4900);
WIRE 16 -1 (-3475 5075)(-3475 4900);
WIRE 16 -1 (-3475 4900)(-3475 4800);
WIRE 16 -1 (-3175 6275)(-2825 6275);
WIRE 16 -1 (-3475 6275)(-3175 6275);
WIRE 16 -1 (-3175 6275)(-3175 6050);
WIRE 16 -1 (-2825 6275)(-2825 6025);
WIRE 16 -1 (-3475 6050)(-3475 6275);
WIRE 16 -1 (-3475 6275)(-3475 6325);
WIRE 16 -1 (-2475 2150)(-1100 2150);
FORCEPROP 2 LAST SIG_NAME RST_RT_CPU0_P0_PERST_R_N
J 0
(-1935 2160);
DISPLAY 0.680851 (-1935 2160);
PAINT SKYBLUE (-1935 2160);
WIRE 16 -1 (-3775 3050)(-2525 3050);
FORCEPROP 2 LAST SIG_NAME JTAG_TEST_MODE_RT_CPU0_P0
J 0
(-3585 3060);
DISPLAY 0.680851 (-3585 3060);
PAINT SKYBLUE (-3585 3060);
WIRE 16 -1 (-3775 2750)(-2450 2750);
FORCEPROP 2 LAST SIG_NAME MODE_RT_CPU0_P0
J 0
(-3460 2760);
DISPLAY 0.680851 (-3460 2760);
PAINT SKYBLUE (-3460 2760);
WIRE 16 -1 (-3775 2550)(-2425 2550);
FORCEPROP 2 LAST SIG_NAME RT_CPU0_P0_SCAN_MODE
J 0
(-3485 2560);
DISPLAY 0.680851 (-3485 2560);
PAINT SKYBLUE (-3485 2560);
WIRE 16 -1 (-3775 2650)(-2450 2650);
FORCEPROP 2 LAST SIG_NAME RXDET_BYP_RT_CPU0_P0
J 0
(-3460 2660);
DISPLAY 0.680851 (-3460 2660);
PAINT WHITE (-3460 2660);
WIRE 16 -1 (-550 3600)(-1350 3600);
FORCEPROP 2 LAST SIG_NAME RXDET_BYP_RT_CPU0_P0
J 0
(-1235 3610);
DISPLAY 0.680851 (-1235 3610);
PAINT WHITE (-1235 3610);
WIRE 16 -1 (-1350 3600)(-1350 3775);
WIRE 16 -1 (-1350 3450)(-1350 3600);
WIRE 16 -1 (-3775 2250)(-2775 2250);
FORCEPROP 2 LAST SIG_NAME CLKREQ_RT_CPU0_P0_N
J 0
(-3510 2260);
DISPLAY 0.680851 (-3510 2260);
PAINT WHITE (-3510 2260);
FORCEPROP 2 LASTPROP $XRERR UNIQUE?
J 0
(-3750 2260);
DISPLAY 0.638298 (-3750 2260);
PAINT MONO (-3750 2260);
DISPLAY INVISIBLE (-3750 2260);
WIRE 16 -1 (-3775 2150)(-2675 2150);
FORCEPROP 2 LAST SIG_NAME RST_RT_CPU0_P0_PERST_N
J 0
(-3610 2160);
DISPLAY 0.680851 (-3610 2160);
PAINT SKYBLUE (-3610 2160);
FORCEPROP 2 LASTPROP $XRERR UNIQUE?
J 0
(-3850 2160);
DISPLAY 0.638298 (-3850 2160);
PAINT MONO (-3850 2160);
DISPLAY INVISIBLE (-3850 2160);
WIRE 16 -1 (-6425 5350)(-7425 5350);
FORCEPROP 2 LAST SIG_NAME JTAG_TEST_MODE_RT_CPU0_P0
J 0
(-7235 5360);
DISPLAY 0.680851 (-7235 5360);
PAINT SKYBLUE (-7235 5360);
WIRE 16 -1 (-7425 5850)(-7425 5350);
WIRE 16 -1 (-7425 5350)(-7425 5050);
WIRE 16 -1 (-7725 5825)(-7725 5425);
WIRE 16 -1 (-6425 5425)(-7725 5425);
FORCEPROP 2 LAST SIG_NAME TEST2_RT_CPU0_P0
J 0
(-6985 5435);
DISPLAY 0.680851 (-6985 5435);
PAINT SKYBLUE (-6985 5435);
WIRE 16 -1 (-7725 5075)(-7725 5425);
WIRE 16 -1 (-8325 5850)(-8325 5525);
WIRE 16 -1 (-6425 5525)(-8325 5525);
FORCEPROP 2 LAST SIG_NAME TEST0_RT_CPU0_P0
J 0
(-6985 5535);
DISPLAY 0.680851 (-6985 5535);
PAINT SKYBLUE (-6985 5535);
WIRE 16 -1 (-8325 5100)(-8325 5525);
WIRE 16 -1 (-8950 5850)(-8950 5650);
WIRE 16 -1 (-6425 5650)(-8950 5650);
FORCEPROP 2 LAST SIG_NAME GPIO2_RT_CPU0_P0
J 0
(-6985 5660);
DISPLAY 0.680851 (-6985 5660);
PAINT SKYBLUE (-6985 5660);
WIRE 16 -1 (-8950 5100)(-8950 5650);
WIRE 16 -1 (-5025 5925)(-5025 5750);
WIRE 16 -1 (-4200 5750)(-5025 5750);
FORCEPROP 2 LAST SIG_NAME MODE_RT_CPU0_P0
J 0
(-4810 5760);
DISPLAY 0.680851 (-4810 5760);
PAINT SKYBLUE (-4810 5760);
WIRE 16 -1 (-5025 5600)(-5025 5750);
WIRE 16 -1 (-1975 5525)(-3175 5525);
FORCEPROP 2 LAST SIG_NAME RT_CPU0_P0_ADDR2
J 0
(-2760 5535);
DISPLAY 0.680851 (-2760 5535);
PAINT SKYBLUE (-2760 5535);
WIRE 16 -1 (-3175 5525)(-3175 5850);
WIRE 16 -1 (-3175 5275)(-3175 5525);
WIRE 16 -1 (-5025 3300)(-5975 3300);
FORCEPROP 2 LAST SIG_NAME GPIO2_RT_CPU0_P0
J 0
(-5835 3310);
DISPLAY 0.680851 (-5835 3310);
PAINT SKYBLUE (-5835 3310);
WIRE 16 -1 (-5025 1000)(-6300 1000);
FORCEPROP 2 LAST SIG_NAME CLK_100M_RETIMER_CPU0_P0_DN
J 0
(-6060 1010);
DISPLAY 0.680851 (-6060 1010);
PAINT SKYBLUE (-6060 1010);
FORCEPROP 2 LASTPROP $XRERR UNIQUE?
J 0
(-6300 1010);
DISPLAY 0.638298 (-6300 1010);
PAINT MONO (-6300 1010);
DISPLAY INVISIBLE (-6300 1010);
WIRE 16 -1 (-6300 1000)(-6300 775);
WIRE 16 -1 (-6300 1000)(-6500 1000);
WIRE 16 -1 (-5025 1150)(-6150 1150);
FORCEPROP 2 LAST SIG_NAME CLK_100M_RETIMER_CPU0_P0_DP
J 0
(-6060 1160);
DISPLAY 0.680851 (-6060 1160);
PAINT SKYBLUE (-6060 1160);
FORCEPROP 2 LASTPROP $XRERR UNIQUE?
J 0
(-6300 1160);
DISPLAY 0.638298 (-6300 1160);
PAINT MONO (-6300 1160);
DISPLAY INVISIBLE (-6300 1160);
WIRE 16 -1 (-6150 1150)(-6500 1150);
WIRE 16 -1 (-6150 1150)(-6150 775);
WIRE 16 -1 (-5025 2600)(-5925 2600);
FORCEPROP 2 LAST SIG_NAME RT_CPU0_P0_ADDR1
J 0
(-5785 2610);
DISPLAY 0.680851 (-5785 2610);
PAINT SKYBLUE (-5785 2610);
WIRE 16 -1 (-5025 2500)(-5925 2500);
FORCEPROP 2 LAST SIG_NAME RT_CPU0_P0_ADDR2
J 0
(-5785 2510);
DISPLAY 0.680851 (-5785 2510);
PAINT SKYBLUE (-5785 2510);
WIRE 16 -1 (-5025 2400)(-5925 2400);
FORCEPROP 2 LAST SIG_NAME RT_CPU0_P0_ADDR3
J 0
(-5785 2410);
DISPLAY 0.680851 (-5785 2410);
PAINT SKYBLUE (-5785 2410);
WIRE 16 -1 (-5025 2850)(-6250 2850);
FORCEPROP 2 LAST SIG_NAME SMB_RT_CPU0_P0_R2_SCL
J 0
(-6010 2860);
DISPLAY 0.680851 (-6010 2860);
PAINT SKYBLUE (-6010 2860);
FORCEPROP 2 LASTPROP $XRERR UNIQUE?
J 0
(-6250 2860);
DISPLAY 0.638298 (-6250 2860);
PAINT MONO (-6250 2860);
DISPLAY INVISIBLE (-6250 2860);
WIRE 16 -1 (-5025 2750)(-6250 2750);
FORCEPROP 2 LAST SIG_NAME SMB_RT_CPU0_P0_R2_SDA
J 0
(-6010 2760);
DISPLAY 0.680851 (-6010 2760);
PAINT SKYBLUE (-6010 2760);
FORCEPROP 2 LASTPROP $XRERR UNIQUE?
J 0
(-6250 2760);
DISPLAY 0.638298 (-6250 2760);
PAINT MONO (-6250 2760);
DISPLAY INVISIBLE (-6250 2760);
WIRE 16 -1 (-5025 2100)(-6100 2100);
FORCEPROP 2 LAST SIG_NAME TEST0_RT_CPU0_P0
J 0
(-5785 2110);
DISPLAY 0.680851 (-5785 2110);
PAINT SKYBLUE (-5785 2110);
WIRE 16 -1 (-5025 2000)(-6100 2000);
FORCEPROP 2 LAST SIG_NAME TEST1_RT_CPU0_P0
J 0
(-5785 2010);
DISPLAY 0.680851 (-5785 2010);
PAINT SKYBLUE (-5785 2010);
WIRE 16 -1 (-5025 1900)(-6100 1900);
FORCEPROP 2 LAST SIG_NAME TEST2_RT_CPU0_P0
J 0
(-5785 1910);
DISPLAY 0.680851 (-5785 1910);
PAINT SKYBLUE (-5785 1910);
WIRE 16 -1 (-8025 5800)(-8025 5475);
WIRE 16 -1 (-6425 5475)(-8025 5475);
FORCEPROP 2 LAST SIG_NAME TEST1_RT_CPU0_P0
J 0
(-6985 5485);
DISPLAY 0.680851 (-6985 5485);
PAINT SKYBLUE (-6985 5485);
WIRE 16 -1 (-8025 5075)(-8025 5475);
WIRE 16 -1 (-1975 5625)(-3475 5625);
FORCEPROP 2 LAST SIG_NAME RT_CPU0_P0_ADDR3
J 0
(-2760 5660);
DISPLAY 0.680851 (-2760 5660);
PAINT SKYBLUE (-2760 5660);
WIRE 16 -1 (-3475 5850)(-3475 5625);
WIRE 16 -1 (-3475 5625)(-3475 5275);
WIRE 16 -1 (-6425 5575)(-8650 5575);
FORCEPROP 2 LAST SIG_NAME GPIO3_RT_CPU0_P0
J 0
(-7010 5585);
DISPLAY 0.680851 (-7010 5585);
PAINT SKYBLUE (-7010 5585);
WIRE 16 -1 (-8650 5575)(-8650 5100);
WIRE 16 -1 (-6450 2750)(-7600 2750);
FORCEPROP 2 LAST SIG_NAME SMB_RT_CPU0_P0_R_SDA
J 0
(-7435 2760);
DISPLAY 0.680851 (-7435 2760);
PAINT SKYBLUE (-7435 2760);
WIRE 16 -1 (-6450 2850)(-7600 2850);
FORCEPROP 2 LAST SIG_NAME SMB_RT_CPU0_P0_R_SCL
J 0
(-7435 2860);
DISPLAY 0.680851 (-7435 2860);
PAINT SKYBLUE (-7435 2860);
WIRE 16 -1 (-1975 5425)(-2825 5425);
FORCEPROP 2 LAST SIG_NAME RT_CPU0_P0_ADDR1
J 0
(-2760 5435);
DISPLAY 0.680851 (-2760 5435);
PAINT SKYBLUE (-2760 5435);
WIRE 16 -1 (-2825 5425)(-2825 5825);
WIRE 16 -1 (-2825 5275)(-2825 5425);
WIRE 16 -1 (-1475 5900)(-1475 5550);
WIRE 16 -1 (-550 5550)(-1475 5550);
FORCEPROP 2 LAST SIG_NAME RST_RT_CPU0_P0_RESET_R_N
J 0
(-1435 5585);
DISPLAY 0.680851 (-1435 5585);
PAINT SKYBLUE (-1435 5585);
WIRE 16 -1 (-1475 5275)(-1475 5550);
WIRE 16 -1 (-1300 5275)(-1300 5400);
FORCEPROP 2 LAST SIG_NAME RST_RT_CPU0_P0_PERST_R_N
J 0
(-1335 5435);
DISPLAY 0.680851 (-1335 5435);
PAINT SKYBLUE (-1335 5435);
WIRE 16 -1 (-1300 5400)(-575 5400);
WIRE 16 -1 (-6700 1150)(-8000 1150);
FORCEPROP 2 LAST SIG_NAME CLK_100M_RETIMER_CPU0_P0_R_DP
J 0
(-7935 1160);
DISPLAY 0.680851 (-7935 1160);
PAINT SKYBLUE (-7935 1160);
WIRE 16 -1 (-6700 1000)(-8000 1000);
FORCEPROP 2 LAST SIG_NAME CLK_100M_RETIMER_CPU0_P0_R_DN
J 0
(-7960 1010);
DISPLAY 0.680851 (-7960 1010);
PAINT SKYBLUE (-7960 1010);
DOT 1 (-3475 4900);
DOT 1 (-6300 1000);
DOT 1 (-6150 1150);
DOT 1 (-8950 6250);
DOT 1 (-8325 4675);
DOT 1 (-8025 4675);
DOT 1 (-8950 5650);
DOT 1 (-8650 4675);
DOT 1 (-8325 5525);
DOT 1 (-7725 4675);
DOT 1 (-8025 5475);
DOT 1 (-7725 5425);
DOT 1 (-8025 6250);
DOT 1 (-7425 4675);
DOT 1 (-5025 5750);
DOT 1 (-3175 4900);
DOT 1 (-3475 6275);
DOT 1 (-3175 6275);
DOT 1 (-1475 5550);
DOT 1 (-8325 6250);
DOT 1 (-7725 6250);
DOT 1 (-3475 5625);
DOT 1 (-2825 5425);
DOT 1 (-3175 5525);
DOT 1 (-1350 3600);
DOT 1 (-7425 5350);
DOT 1 (-8975 3850);
DOT 1 (-1200 1700);
DOT 1 (-650 1200);
DOT 1 (-925 1700);
DOT 1 (-650 1700);
FORCENOTE
CPU1 P0 RT ADDR: 0X48 (8-BIT) / 0X24 (7-BIT)
(-4275 4575) 0;
DISPLAY LEFT (-4275 4575);
DISPLAY 1.595745 (-4275 4575);
QUIT
